FILE_TYPE = MACRO_DRAWING;
SET COLOR_WIRE YELLOW;
SET COLOR_PROP ORANGE;
SET COLOR_DOT WHITE;
SET COLOR_ARC YELLOW;
SET COLOR_BODY GREEN;
SET COLOR_NOTE PURPLE;
SET PROP_DISPLAY VALUE;
SET PAGE_NUMBER P187;
FORCEADD OFFPAGE..1
(-7725 1475);
FORCEPROP 2 LAST $XR5 216 
J 0
(-8577 1475);
DISPLAY 0.638298 (-8577 1475);
PAINT MONO (-8577 1475);
FORCEPROP 2 LAST $XR4 215 
J 0
(-8457 1475);
DISPLAY 0.638298 (-8457 1475);
PAINT MONO (-8457 1475);
FORCEPROP 2 LAST $XR3 213 
J 0
(-8337 1475);
DISPLAY 0.638298 (-8337 1475);
PAINT MONO (-8337 1475);
FORCEPROP 2 LAST $XR2 212 
J 0
(-8217 1475);
DISPLAY 0.638298 (-8217 1475);
PAINT MONO (-8217 1475);
FORCEPROP 2 LAST $XR1 211 
J 0
(-8097 1475);
DISPLAY 0.638298 (-8097 1475);
PAINT MONO (-8097 1475);
FORCEPROP 2 LAST $XR0 210 
J 0
(-7977 1475);
DISPLAY 0.638298 (-7977 1475);
PAINT MONO (-7977 1475);
FORCEPROP 2 LAST CDS_LIB standard
J 0
(-7725 1475);
DISPLAY INVISIBLE (-7725 1475);
FORCEPROP 1 LAST OFFPAGE TRUE
J 0
(-7400 1350);
DISPLAY 0.872340 (-7400 1350);
PAINT GREEN (-7400 1350);
DISPLAY INVISIBLE (-7400 1350);
FORCEPROP 1 LAST COMMENT_BODY TRUE
J 0
(-7600 1375);
DISPLAY 0.872340 (-7600 1375);
PAINT GREEN (-7600 1375);
DISPLAY INVISIBLE (-7600 1375);
FORCEPROP 2 LAST PATH I1
J 0
(-8000 1525);
DISPLAY 0.680851 (-8000 1525);
DISPLAY INVISIBLE (-8000 1525);
FORCEADD OFFPAGE..2
R 2
(-6800 1075);
FORCEPROP 2 LAST $XR3 210 
J 0
(-7295 1039);
DISPLAY 0.638298 (-7295 1039);
PAINT MONO (-7295 1039);
FORCEPROP 2 LAST $XR2 213 
J 0
(-7175 1039);
DISPLAY 0.638298 (-7175 1039);
PAINT MONO (-7175 1039);
FORCEPROP 2 LAST $XR1 212 
J 0
(-7055 1039);
DISPLAY 0.638298 (-7055 1039);
PAINT MONO (-7055 1039);
FORCEPROP 2 LAST $XR0 211 
J 0
(-7055 1075);
DISPLAY 0.638298 (-7055 1075);
PAINT MONO (-7055 1075);
FORCEPROP 2 LAST CDS_LIB standard
J 0
(-6800 1075);
DISPLAY INVISIBLE (-6800 1075);
FORCEPROP 1 LAST OFFPAGE TRUE
J 2
(-7125 950);
DISPLAY 0.872340 (-7125 950);
PAINT GREEN (-7125 950);
DISPLAY INVISIBLE (-7125 950);
FORCEPROP 1 LAST COMMENT_BODY TRUE
J 2
(-6755 980);
DISPLAY 0.872340 (-6755 980);
PAINT GREEN (-6755 980);
DISPLAY INVISIBLE (-6755 980);
FORCEPROP 2 LAST PATH I10
J 0
(-7050 1125);
DISPLAY 0.680851 (-7050 1125);
DISPLAY INVISIBLE (-7050 1125);
FORCEADD Q_RES..1
(-6850 1275);
FORCEPROP 1 LAST LOCATION PR196
J 0
(-6900 1325);
DISPLAY 0.489362 (-6900 1325);
PAINT SKYBLUE (-6900 1325);
FORCEPROP 0 LAST $SEC 1
J 0
(-6850 1350);
DISPLAY 0.680851 (-6850 1350);
PAINT MONO (-6850 1350);
DISPLAY INVISIBLE (-6850 1350);
FORCEPROP 0 LAST CDS_SEC 1
J 0
(-6850 1350);
DISPLAY 1.021277 (-6850 1350);
DISPLAY INVISIBLE (-6850 1350);
FORCEPROP 1 LASTPIN (-6950 1275) $PN 1
J 0
(-6938 1287);
DISPLAY 0.489362 (-6938 1287);
PAINT MONO (-6938 1287);
FORCEPROP 1 LASTPIN (-6750 1275) $PN 2
J 0
(-6788 1287);
DISPLAY 0.489362 (-6788 1287);
PAINT MONO (-6788 1287);
FORCEPROP 1 LAST PACK_TYPE 0402LF
J 0
(-6750 1225);
DISPLAY 0.489362 (-6750 1225);
PAINT SKYBLUE (-6750 1225);
FORCEPROP 1 LAST MATERIAL EMPTY
J 0
(-7150 1175);
DISPLAY 0.489362 (-7150 1175);
PAINT RED (-7150 1175);
FORCEPROP 1 LAST WATTAGE 1/16W
J 0
(-6750 1175);
DISPLAY 0.489362 (-6750 1175);
PAINT SKYBLUE (-6750 1175);
FORCEPROP 1 LAST TOLERANCE 1%
J 0
(-6725 1300);
DISPLAY 0.489362 (-6725 1300);
PAINT SKYBLUE (-6725 1300);
FORCEPROP 1 LAST VALUE 8.87K
J 2
(-6975 1300);
DISPLAY 0.489362 (-6975 1300);
PAINT SKYBLUE (-6975 1300);
FORCEPROP 2 LAST CDS_LIB pure_quanta
J 0
(-6850 1275);
DISPLAY INVISIBLE (-6850 1275);
FORCEPROP 1 LAST PATH I11
J 0
(-6900 1425);
DISPLAY 0.978723 (-6900 1425);
PAINT WHITE (-6900 1425);
DISPLAY INVISIBLE (-6900 1425);
FORCEPROP 1 LAST PART_NUMBER CS28872FB01
J 0
(-7150 1225);
DISPLAY 0.489362 (-7150 1225);
PAINT SKYBLUE (-7150 1225);
DISPLAY INVISIBLE (-7150 1225);
FORCEADD Q_RES..2
(-7150 2475);
FORCEPROP 1 LAST LOCATION PR194
J 0
(-7105 2600);
DISPLAY 0.489362 (-7105 2600);
PAINT SKYBLUE (-7105 2600);
FORCEPROP 0 LAST $SEC 1
J 0
(-7100 2650);
DISPLAY 0.680851 (-7100 2650);
PAINT MONO (-7100 2650);
DISPLAY INVISIBLE (-7100 2650);
FORCEPROP 0 LAST CDS_SEC 1
J 0
(-7100 2650);
DISPLAY 1.021277 (-7100 2650);
DISPLAY INVISIBLE (-7100 2650);
FORCEPROP 1 LASTPIN (-7150 2575) $PN 1
J 0
(-7145 2537);
DISPLAY 0.489362 (-7145 2537);
PAINT MONO (-7145 2537);
FORCEPROP 1 LASTPIN (-7150 2375) $PN 2
J 0
(-7145 2385);
DISPLAY 0.489362 (-7145 2385);
PAINT MONO (-7145 2385);
FORCEPROP 1 LAST PACK_TYPE 0402LF
J 0
(-7100 2300);
DISPLAY 0.489362 (-7100 2300);
PAINT SKYBLUE (-7100 2300);
FORCEPROP 1 LAST VALUE 2.2
J 0
(-7100 2550);
DISPLAY 0.489362 (-7100 2550);
PAINT SKYBLUE (-7100 2550);
FORCEPROP 1 LAST TOLERANCE 1%
J 0
(-7100 2500);
DISPLAY 0.489362 (-7100 2500);
PAINT SKYBLUE (-7100 2500);
FORCEPROP 1 LAST MATERIAL CHIP
J 0
(-7100 2400);
DISPLAY 0.489362 (-7100 2400);
PAINT SKYBLUE (-7100 2400);
FORCEPROP 1 LAST WATTAGE 1/16W
J 0
(-7100 2450);
DISPLAY 0.489362 (-7100 2450);
PAINT SKYBLUE (-7100 2450);
FORCEPROP 2 LAST CDS_LIB pure_quanta
J 0
(-7150 2475);
DISPLAY INVISIBLE (-7150 2475);
FORCEPROP 1 LAST PATH I12
J 0
(-7100 2650);
DISPLAY 0.978723 (-7100 2650);
PAINT WHITE (-7100 2650);
DISPLAY INVISIBLE (-7100 2650);
FORCEPROP 1 LAST PART_NUMBER CS-2202FB01
J 0
(-7100 2350);
DISPLAY 0.489362 (-7100 2350);
PAINT SKYBLUE (-7100 2350);
DISPLAY INVISIBLE (-7100 2350);
FORCEADD VCC_CORE..1
(-7150 2875);
FORCEPROP 3 LASTPIN (-7150 2825) SIG_NAME PVDDCR_CPU0_P1_PVCC\g
J 0
(-7140 2835);
DISPLAY 0.659574 (-7140 2835);
PAINT MONO (-7140 2835);
DISPLAY INVISIBLE (-7140 2835);
FORCEPROP 1 LAST HDL_POWER PVDDCR_CPU0_P1_PVCC
J 1
(-7150 2925);
DISPLAY 0.489362 (-7150 2925);
PAINT GREEN (-7150 2925);
FORCEPROP 2 LAST CDS_LIB pure_quanta_power
J 0
(-7150 2875);
DISPLAY INVISIBLE (-7150 2875);
FORCEPROP 1 LAST PATH I13
J 0
(-7100 2900);
DISPLAY 0.872340 (-7100 2900);
PAINT AQUA (-7100 2900);
DISPLAY INVISIBLE (-7100 2900);
FORCEADD UNIVERSAL_GND..1
(-6800 2225);
FORCEPROP 3 LASTPIN (-6800 2275) SIG_NAME GND\g
J 0
(-6790 2285);
DISPLAY 0.659574 (-6790 2285);
PAINT MONO (-6790 2285);
DISPLAY INVISIBLE (-6790 2285);
FORCEPROP 2 LAST CDS_LIB pure_quanta_power
J 0
(-6800 2225);
DISPLAY INVISIBLE (-6800 2225);
FORCEPROP 1 LAST HDL_POWER GND
J 1
(-6775 2150);
DISPLAY 0.872340 (-6775 2150);
PAINT GREEN (-6775 2150);
DISPLAY INVISIBLE (-6775 2150);
FORCEPROP 1 LAST PATH I14
J 0
(-6725 2225);
DISPLAY 0.872340 (-6725 2225);
PAINT AQUA (-6725 2225);
DISPLAY INVISIBLE (-6725 2225);
FORCEADD Q_CAP..1
(-6800 2500);
FORCEPROP 1 LAST LOCATION PC289_C0P1_4
J 0
(-6750 2600);
DISPLAY 0.489362 (-6750 2600);
PAINT SKYBLUE (-6750 2600);
FORCEPROP 0 LAST $SEC 1
J 0
(-6750 2650);
DISPLAY 0.680851 (-6750 2650);
PAINT MONO (-6750 2650);
DISPLAY INVISIBLE (-6750 2650);
FORCEPROP 0 LAST CDS_SEC 1
J 0
(-6750 2650);
DISPLAY 1.021277 (-6750 2650);
DISPLAY INVISIBLE (-6750 2650);
FORCEPROP 1 LASTPIN (-6800 2600) $PN 1
J 0
(-6790 2580);
DISPLAY 0.489362 (-6790 2580);
PAINT MONO (-6790 2580);
FORCEPROP 1 LASTPIN (-6800 2400) $PN 2
J 0
(-6790 2380);
DISPLAY 0.489362 (-6790 2380);
PAINT MONO (-6790 2380);
FORCEPROP 1 LAST PACK_TYPE C0402
J 0
(-6750 2300);
DISPLAY 0.489362 (-6750 2300);
PAINT SKYBLUE (-6750 2300);
FORCEPROP 1 LAST VOLTAGE 10V
J 0
(-6750 2500);
DISPLAY 0.489362 (-6750 2500);
PAINT SKYBLUE (-6750 2500);
FORCEPROP 1 LAST VALUE 2.2UF
J 0
(-6750 2550);
DISPLAY 0.489362 (-6750 2550);
PAINT SKYBLUE (-6750 2550);
FORCEPROP 1 LAST MATERIAL X6S
J 0
(-6750 2400);
DISPLAY 0.489362 (-6750 2400);
PAINT SKYBLUE (-6750 2400);
FORCEPROP 1 LAST TOLERANCE 10%
J 0
(-6750 2450);
DISPLAY 0.489362 (-6750 2450);
PAINT SKYBLUE (-6750 2450);
FORCEPROP 2 LAST CDS_LIB pure_quanta
J 0
(-6800 2500);
DISPLAY INVISIBLE (-6800 2500);
FORCEPROP 1 LAST PATH I15
J 0
(-6750 2650);
DISPLAY 0.978723 (-6750 2650);
PAINT WHITE (-6750 2650);
DISPLAY INVISIBLE (-6750 2650);
FORCEPROP 1 LAST PART_NUMBER CH5222KEB01
J 0
(-6750 2350);
DISPLAY 0.489362 (-6750 2350);
PAINT SKYBLUE (-6750 2350);
DISPLAY INVISIBLE (-6750 2350);
FORCEADD UNIVERSAL_GND..1
(-5125 825);
FORCEPROP 3 LASTPIN (-5125 875) SIG_NAME GND\g
J 0
(-5115 885);
DISPLAY 0.659574 (-5115 885);
PAINT MONO (-5115 885);
DISPLAY INVISIBLE (-5115 885);
FORCEPROP 2 LAST CDS_LIB pure_quanta_power
J 0
(-5125 825);
DISPLAY INVISIBLE (-5125 825);
FORCEPROP 1 LAST HDL_POWER GND
J 1
(-5100 750);
DISPLAY 0.872340 (-5100 750);
PAINT GREEN (-5100 750);
DISPLAY INVISIBLE (-5100 750);
FORCEPROP 1 LAST PATH I16
J 0
(-5050 825);
DISPLAY 0.872340 (-5050 825);
PAINT AQUA (-5050 825);
DISPLAY INVISIBLE (-5050 825);
FORCEADD Q_RES..1
(-3925 475);
FORCEPROP 1 LAST LOCATION PR200
J 0
(-3950 525);
DISPLAY 0.489362 (-3950 525);
PAINT SKYBLUE (-3950 525);
FORCEPROP 0 LAST $SEC 1
J 0
(-3925 550);
DISPLAY 0.680851 (-3925 550);
PAINT MONO (-3925 550);
DISPLAY INVISIBLE (-3925 550);
FORCEPROP 0 LAST CDS_SEC 1
J 0
(-3925 550);
DISPLAY 1.021277 (-3925 550);
DISPLAY INVISIBLE (-3925 550);
FORCEPROP 1 LASTPIN (-4025 475) $PN 1
J 0
(-4013 487);
DISPLAY 0.489362 (-4013 487);
PAINT MONO (-4013 487);
FORCEPROP 1 LASTPIN (-3825 475) $PN 2
J 0
(-3863 487);
DISPLAY 0.489362 (-3863 487);
PAINT MONO (-3863 487);
FORCEPROP 1 LAST WATTAGE 1/16W
J 0
(-3825 425);
DISPLAY 0.489362 (-3825 425);
PAINT SKYBLUE (-3825 425);
FORCEPROP 1 LAST MATERIAL CHIP
J 0
(-4175 375);
DISPLAY 0.489362 (-4175 375);
PAINT SKYBLUE (-4175 375);
FORCEPROP 1 LAST TOLERANCE 5%
J 0
(-3800 500);
DISPLAY 0.489362 (-3800 500);
PAINT SKYBLUE (-3800 500);
FORCEPROP 1 LAST VALUE 0
J 2
(-4050 500);
DISPLAY 0.489362 (-4050 500);
PAINT SKYBLUE (-4050 500);
FORCEPROP 1 LAST PACK_TYPE 0402LF
J 0
(-3825 375);
DISPLAY 0.489362 (-3825 375);
PAINT SKYBLUE (-3825 375);
FORCEPROP 2 LAST CDS_LIB pure_quanta
J 0
(-3925 475);
DISPLAY INVISIBLE (-3925 475);
FORCEPROP 1 LAST PATH I17
J 0
(-3975 625);
DISPLAY 0.978723 (-3975 625);
PAINT WHITE (-3975 625);
DISPLAY INVISIBLE (-3975 625);
FORCEPROP 1 LAST PART_NUMBER CS00002JB13
J 0
(-4175 425);
DISPLAY 0.489362 (-4175 425);
PAINT SKYBLUE (-4175 425);
DISPLAY INVISIBLE (-4175 425);
FORCEADD UNIVERSAL_GND..1
(-4250 650);
FORCEPROP 3 LASTPIN (-4250 700) SIG_NAME GND\g
J 0
(-4240 710);
DISPLAY 0.659574 (-4240 710);
PAINT MONO (-4240 710);
DISPLAY INVISIBLE (-4240 710);
FORCEPROP 2 LAST CDS_LIB pure_quanta_power
J 0
(-4250 650);
DISPLAY INVISIBLE (-4250 650);
FORCEPROP 1 LAST HDL_POWER GND
J 1
(-4225 575);
DISPLAY 0.872340 (-4225 575);
PAINT GREEN (-4225 575);
DISPLAY INVISIBLE (-4225 575);
FORCEPROP 1 LAST PATH I18
J 0
(-4175 650);
DISPLAY 0.872340 (-4175 650);
PAINT AQUA (-4175 650);
DISPLAY INVISIBLE (-4175 650);
FORCEADD Q_RES..2
(-4250 875);
FORCEPROP 1 LAST LOCATION PR523
J 0
(-4205 1000);
DISPLAY 0.489362 (-4205 1000);
PAINT SKYBLUE (-4205 1000);
FORCEPROP 0 LAST $SEC 1
J 0
(-4200 1050);
DISPLAY 0.680851 (-4200 1050);
PAINT MONO (-4200 1050);
DISPLAY INVISIBLE (-4200 1050);
FORCEPROP 0 LAST CDS_SEC 1
J 0
(-4200 1050);
DISPLAY 1.021277 (-4200 1050);
DISPLAY INVISIBLE (-4200 1050);
FORCEPROP 1 LASTPIN (-4250 975) $PN 1
J 0
(-4245 937);
DISPLAY 0.489362 (-4245 937);
PAINT MONO (-4245 937);
FORCEPROP 1 LASTPIN (-4250 775) $PN 2
J 0
(-4245 785);
DISPLAY 0.489362 (-4245 785);
PAINT MONO (-4245 785);
FORCEPROP 1 LAST PACK_TYPE 0402LF
J 0
(-4210 700);
DISPLAY 0.489362 (-4210 700);
PAINT SKYBLUE (-4210 700);
FORCEPROP 1 LAST VALUE 1.5
J 0
(-4205 950);
DISPLAY 0.489362 (-4205 950);
PAINT SKYBLUE (-4205 950);
FORCEPROP 1 LAST TOLERANCE 1%
J 0
(-4205 900);
DISPLAY 0.489362 (-4205 900);
PAINT SKYBLUE (-4205 900);
FORCEPROP 1 LAST MATERIAL EMPTY
J 0
(-4210 800);
DISPLAY 0.489362 (-4210 800);
PAINT RED (-4210 800);
FORCEPROP 1 LAST WATTAGE 1/8W
J 0
(-4210 850);
DISPLAY 0.489362 (-4210 850);
PAINT SKYBLUE (-4210 850);
FORCEPROP 2 LAST CDS_LIB pure_quanta
J 0
(-4250 875);
DISPLAY INVISIBLE (-4250 875);
FORCEPROP 1 LAST PATH I19
J 0
(-4200 1050);
DISPLAY 0.978723 (-4200 1050);
PAINT WHITE (-4200 1050);
DISPLAY INVISIBLE (-4200 1050);
FORCEPROP 1 LAST PART_NUMBER CS-1504FB00
J 0
(-4210 750);
DISPLAY 0.489362 (-4210 750);
PAINT SKYBLUE (-4210 750);
DISPLAY INVISIBLE (-4210 750);
FORCEADD Q_CAP..1
(-7500 1300);
FORCEPROP 1 LAST LOCATION PC285_4
J 0
(-7450 1400);
DISPLAY 0.489362 (-7450 1400);
PAINT SKYBLUE (-7450 1400);
FORCEPROP 0 LAST $SEC 1
J 0
(-7450 1425);
DISPLAY 0.680851 (-7450 1425);
PAINT MONO (-7450 1425);
DISPLAY INVISIBLE (-7450 1425);
FORCEPROP 0 LAST CDS_SEC 1
J 0
(-7450 1425);
DISPLAY 1.021277 (-7450 1425);
DISPLAY INVISIBLE (-7450 1425);
FORCEPROP 1 LASTPIN (-7500 1400) $PN 1
J 0
(-7490 1380);
DISPLAY 0.489362 (-7490 1380);
PAINT MONO (-7490 1380);
FORCEPROP 1 LASTPIN (-7500 1200) $PN 2
J 0
(-7490 1180);
DISPLAY 0.489362 (-7490 1180);
PAINT MONO (-7490 1180);
FORCEPROP 1 LAST PACK_TYPE 0402
J 0
(-7450 1100);
DISPLAY 0.489362 (-7450 1100);
PAINT SKYBLUE (-7450 1100);
FORCEPROP 1 LAST VOLTAGE 25V
J 0
(-7450 1300);
DISPLAY 0.489362 (-7450 1300);
PAINT SKYBLUE (-7450 1300);
FORCEPROP 1 LAST VALUE 0.1UF
J 0
(-7450 1350);
DISPLAY 0.489362 (-7450 1350);
PAINT SKYBLUE (-7450 1350);
FORCEPROP 1 LAST TOLERANCE 10%
J 0
(-7450 1250);
DISPLAY 0.489362 (-7450 1250);
PAINT SKYBLUE (-7450 1250);
FORCEPROP 1 LAST MATERIAL X7R
J 0
(-7450 1200);
DISPLAY 0.489362 (-7450 1200);
PAINT SKYBLUE (-7450 1200);
FORCEPROP 2 LAST CDS_LIB pure_quanta
J 0
(-7500 1300);
DISPLAY INVISIBLE (-7500 1300);
FORCEPROP 1 LAST PATH I2
J 0
(-7450 1450);
DISPLAY 0.978723 (-7450 1450);
PAINT WHITE (-7450 1450);
DISPLAY INVISIBLE (-7450 1450);
FORCEPROP 1 LAST PART_NUMBER CH4104K1B00
J 0
(-7450 1150);
DISPLAY 0.489362 (-7450 1150);
PAINT SKYBLUE (-7450 1150);
DISPLAY INVISIBLE (-7450 1150);
FORCEADD Q_CAP..1
(-4250 1375);
FORCEPROP 1 LAST LOCATION PC317
J 0
(-4200 1475);
DISPLAY 0.489362 (-4200 1475);
PAINT SKYBLUE (-4200 1475);
FORCEPROP 0 LAST $SEC 1
J 0
(-4200 1525);
DISPLAY 0.680851 (-4200 1525);
PAINT MONO (-4200 1525);
DISPLAY INVISIBLE (-4200 1525);
FORCEPROP 0 LAST CDS_SEC 1
J 0
(-4200 1525);
DISPLAY 1.021277 (-4200 1525);
DISPLAY INVISIBLE (-4200 1525);
FORCEPROP 1 LASTPIN (-4250 1475) $PN 1
J 0
(-4240 1455);
DISPLAY 0.489362 (-4240 1455);
PAINT MONO (-4240 1455);
FORCEPROP 1 LASTPIN (-4250 1275) $PN 2
J 0
(-4240 1255);
DISPLAY 0.489362 (-4240 1255);
PAINT MONO (-4240 1255);
FORCEPROP 1 LAST PACK_TYPE C0402
J 0
(-4200 1175);
DISPLAY 0.489362 (-4200 1175);
PAINT SKYBLUE (-4200 1175);
FORCEPROP 1 LAST VOLTAGE 50V
J 0
(-4200 1375);
DISPLAY 0.489362 (-4200 1375);
PAINT SKYBLUE (-4200 1375);
FORCEPROP 1 LAST VALUE 560PF
J 0
(-4200 1425);
DISPLAY 0.489362 (-4200 1425);
PAINT SKYBLUE (-4200 1425);
FORCEPROP 1 LAST TOLERANCE 10%
J 0
(-4200 1325);
DISPLAY 0.489362 (-4200 1325);
PAINT SKYBLUE (-4200 1325);
FORCEPROP 1 LAST MATERIAL EMPTY
J 0
(-4200 1275);
DISPLAY 0.489362 (-4200 1275);
PAINT RED (-4200 1275);
FORCEPROP 2 LAST CDS_LIB pure_quanta
J 0
(-4250 1375);
DISPLAY INVISIBLE (-4250 1375);
FORCEPROP 1 LAST PATH I20
J 0
(-4200 1525);
DISPLAY 0.978723 (-4200 1525);
PAINT WHITE (-4200 1525);
DISPLAY INVISIBLE (-4200 1525);
FORCEPROP 1 LAST PART_NUMBER CH1566K1B09
J 0
(-4200 1225);
DISPLAY 0.489362 (-4200 1225);
PAINT SKYBLUE (-4200 1225);
DISPLAY INVISIBLE (-4200 1225);
FORCEADD Q_RES..1
(-4300 1925);
FORCEPROP 1 LAST LOCATION PR198
J 0
(-4325 1975);
DISPLAY 0.489362 (-4325 1975);
PAINT SKYBLUE (-4325 1975);
FORCEPROP 0 LAST $SEC 1
J 0
(-4275 2000);
DISPLAY 0.680851 (-4275 2000);
PAINT MONO (-4275 2000);
DISPLAY INVISIBLE (-4275 2000);
FORCEPROP 0 LAST CDS_SEC 1
J 0
(-4275 2000);
DISPLAY 1.021277 (-4275 2000);
DISPLAY INVISIBLE (-4275 2000);
FORCEPROP 1 LASTPIN (-4400 1925) $PN 1
J 0
(-4388 1937);
DISPLAY 0.489362 (-4388 1937);
PAINT MONO (-4388 1937);
FORCEPROP 1 LASTPIN (-4200 1925) $PN 2
J 0
(-4238 1937);
DISPLAY 0.489362 (-4238 1937);
PAINT MONO (-4238 1937);
FORCEPROP 1 LAST TOLERANCE 1%
J 0
(-4200 1950);
DISPLAY 0.489362 (-4200 1950);
PAINT SKYBLUE (-4200 1950);
FORCEPROP 1 LAST PACK_TYPE 0402LF
J 0
(-4200 1825);
DISPLAY 0.489362 (-4200 1825);
PAINT SKYBLUE (-4200 1825);
FORCEPROP 1 LAST MATERIAL CHIP
J 0
(-4550 1825);
DISPLAY 0.489362 (-4550 1825);
PAINT SKYBLUE (-4550 1825);
FORCEPROP 1 LAST WATTAGE 1/16W
J 0
(-4200 1875);
DISPLAY 0.489362 (-4200 1875);
PAINT SKYBLUE (-4200 1875);
FORCEPROP 1 LAST VALUE 5.6
J 2
(-4400 1950);
DISPLAY 0.489362 (-4400 1950);
PAINT SKYBLUE (-4400 1950);
FORCEPROP 2 LAST CDS_LIB pure_quanta
J 0
(-4300 1925);
DISPLAY INVISIBLE (-4300 1925);
FORCEPROP 1 LAST PATH I21
J 0
(-4350 2075);
DISPLAY 0.978723 (-4350 2075);
PAINT WHITE (-4350 2075);
DISPLAY INVISIBLE (-4350 2075);
FORCEPROP 1 LAST PART_NUMBER CS-5602FB01
J 0
(-4550 1875);
DISPLAY 0.489362 (-4550 1875);
PAINT SKYBLUE (-4550 1875);
DISPLAY INVISIBLE (-4550 1875);
FORCEADD Q_CAP..1
(-5000 2475);
FORCEPROP 1 LAST LOCATION PC293_4
J 0
(-4950 2575);
DISPLAY 0.489362 (-4950 2575);
PAINT SKYBLUE (-4950 2575);
FORCEPROP 0 LAST $SEC 1
J 0
(-4950 2625);
DISPLAY 0.680851 (-4950 2625);
PAINT MONO (-4950 2625);
DISPLAY INVISIBLE (-4950 2625);
FORCEPROP 0 LAST CDS_SEC 1
J 0
(-4950 2625);
DISPLAY 1.021277 (-4950 2625);
DISPLAY INVISIBLE (-4950 2625);
FORCEPROP 1 LASTPIN (-5000 2575) $PN 1
J 0
(-4990 2555);
DISPLAY 0.489362 (-4990 2555);
PAINT MONO (-4990 2555);
FORCEPROP 1 LASTPIN (-5000 2375) $PN 2
J 0
(-4990 2355);
DISPLAY 0.489362 (-4990 2355);
PAINT MONO (-4990 2355);
FORCEPROP 1 LAST PACK_TYPE 0402
J 0
(-4950 2275);
DISPLAY 0.489362 (-4950 2275);
PAINT SKYBLUE (-4950 2275);
FORCEPROP 1 LAST VOLTAGE 25V
J 0
(-4950 2475);
DISPLAY 0.489362 (-4950 2475);
PAINT SKYBLUE (-4950 2475);
FORCEPROP 1 LAST VALUE 0.1UF
J 0
(-4950 2525);
DISPLAY 0.489362 (-4950 2525);
PAINT SKYBLUE (-4950 2525);
FORCEPROP 1 LAST TOLERANCE 10%
J 0
(-4950 2425);
DISPLAY 0.489362 (-4950 2425);
PAINT SKYBLUE (-4950 2425);
FORCEPROP 1 LAST MATERIAL X7R
J 0
(-4950 2375);
DISPLAY 0.489362 (-4950 2375);
PAINT SKYBLUE (-4950 2375);
FORCEPROP 2 LAST CDS_LIB pure_quanta
J 0
(-5000 2475);
DISPLAY INVISIBLE (-5000 2475);
FORCEPROP 1 LAST PATH I22
J 0
(-4950 2625);
DISPLAY 0.978723 (-4950 2625);
PAINT WHITE (-4950 2625);
DISPLAY INVISIBLE (-4950 2625);
FORCEPROP 1 LAST PART_NUMBER CH4104K1B00
J 0
(-4950 2325);
DISPLAY 0.489362 (-4950 2325);
PAINT SKYBLUE (-4950 2325);
DISPLAY INVISIBLE (-4950 2325);
FORCEADD Q_CAP..1
(-4625 2475);
FORCEPROP 1 LAST LOCATION PC291_4
J 0
(-4575 2575);
DISPLAY 0.489362 (-4575 2575);
PAINT SKYBLUE (-4575 2575);
FORCEPROP 0 LAST $SEC 1
J 0
(-4575 2600);
DISPLAY 0.680851 (-4575 2600);
PAINT MONO (-4575 2600);
DISPLAY INVISIBLE (-4575 2600);
FORCEPROP 0 LAST CDS_SEC 1
J 0
(-4575 2600);
DISPLAY 1.021277 (-4575 2600);
DISPLAY INVISIBLE (-4575 2600);
FORCEPROP 1 LASTPIN (-4625 2575) $PN 1
J 0
(-4615 2555);
DISPLAY 0.489362 (-4615 2555);
PAINT MONO (-4615 2555);
FORCEPROP 1 LASTPIN (-4625 2375) $PN 2
J 0
(-4615 2355);
DISPLAY 0.489362 (-4615 2355);
PAINT MONO (-4615 2355);
FORCEPROP 1 LAST TOLERANCE 10%
J 0
(-4575 2425);
DISPLAY 0.489362 (-4575 2425);
PAINT SKYBLUE (-4575 2425);
FORCEPROP 1 LAST VOLTAGE 25V
J 0
(-4575 2475);
DISPLAY 0.489362 (-4575 2475);
PAINT SKYBLUE (-4575 2475);
FORCEPROP 1 LAST VALUE 1UF
J 0
(-4575 2525);
DISPLAY 0.489362 (-4575 2525);
PAINT SKYBLUE (-4575 2525);
FORCEPROP 1 LAST MATERIAL X6S
J 0
(-4575 2375);
DISPLAY 0.489362 (-4575 2375);
PAINT SKYBLUE (-4575 2375);
FORCEPROP 1 LAST PACK_TYPE C0402
J 0
(-4575 2275);
DISPLAY 0.489362 (-4575 2275);
PAINT SKYBLUE (-4575 2275);
FORCEPROP 2 LAST CDS_LIB pure_quanta
J 0
(-4625 2475);
DISPLAY INVISIBLE (-4625 2475);
FORCEPROP 1 LAST PATH I23
J 0
(-4575 2625);
DISPLAY 0.978723 (-4575 2625);
PAINT WHITE (-4575 2625);
DISPLAY INVISIBLE (-4575 2625);
FORCEPROP 1 LAST PART_NUMBER CH5104KEB02
J 0
(-4575 2325);
DISPLAY 0.489362 (-4575 2325);
PAINT SKYBLUE (-4575 2325);
DISPLAY INVISIBLE (-4575 2325);
FORCEADD Q_CAP..1
(-4300 2475);
FORCEPROP 1 LAST LOCATION PC295_4
J 0
(-4250 2575);
DISPLAY 0.489362 (-4250 2575);
PAINT SKYBLUE (-4250 2575);
FORCEPROP 0 LAST $SEC 1
J 0
(-4250 2600);
DISPLAY 0.680851 (-4250 2600);
PAINT MONO (-4250 2600);
DISPLAY INVISIBLE (-4250 2600);
FORCEPROP 0 LAST CDS_SEC 1
J 0
(-4250 2600);
DISPLAY 1.021277 (-4250 2600);
DISPLAY INVISIBLE (-4250 2600);
FORCEPROP 1 LASTPIN (-4300 2575) $PN 1
J 0
(-4290 2555);
DISPLAY 0.489362 (-4290 2555);
PAINT MONO (-4290 2555);
FORCEPROP 1 LASTPIN (-4300 2375) $PN 2
J 0
(-4290 2355);
DISPLAY 0.489362 (-4290 2355);
PAINT MONO (-4290 2355);
FORCEPROP 1 LAST PACK_TYPE C0805
J 0
(-4250 2275);
DISPLAY 0.489362 (-4250 2275);
PAINT SKYBLUE (-4250 2275);
FORCEPROP 1 LAST VALUE 22UF
J 0
(-4250 2525);
DISPLAY 0.489362 (-4250 2525);
PAINT SKYBLUE (-4250 2525);
FORCEPROP 1 LAST MATERIAL X6S
J 0
(-4250 2375);
DISPLAY 0.489362 (-4250 2375);
PAINT SKYBLUE (-4250 2375);
FORCEPROP 1 LAST VOLTAGE 16V
J 0
(-4250 2475);
DISPLAY 0.489362 (-4250 2475);
PAINT SKYBLUE (-4250 2475);
FORCEPROP 1 LAST TOLERANCE 20%
J 0
(-4250 2425);
DISPLAY 0.489362 (-4250 2425);
PAINT SKYBLUE (-4250 2425);
FORCEPROP 2 LAST CDS_LIB pure_quanta
J 0
(-4300 2475);
DISPLAY INVISIBLE (-4300 2475);
FORCEPROP 1 LAST PATH I24
J 0
(-4250 2625);
DISPLAY 0.978723 (-4250 2625);
PAINT WHITE (-4250 2625);
DISPLAY INVISIBLE (-4250 2625);
FORCEPROP 1 LAST PART_NUMBER CH6223MEA01
J 0
(-4250 2325);
DISPLAY 0.489362 (-4250 2325);
PAINT SKYBLUE (-4250 2325);
DISPLAY INVISIBLE (-4250 2325);
FORCEADD Q_CAP..1
(-3975 2475);
FORCEPROP 1 LAST LOCATION PC297_4
J 0
(-3925 2575);
DISPLAY 0.489362 (-3925 2575);
PAINT SKYBLUE (-3925 2575);
FORCEPROP 0 LAST $SEC 1
J 0
(-3925 2600);
DISPLAY 0.680851 (-3925 2600);
PAINT MONO (-3925 2600);
DISPLAY INVISIBLE (-3925 2600);
FORCEPROP 0 LAST CDS_SEC 1
J 0
(-3925 2600);
DISPLAY 1.021277 (-3925 2600);
DISPLAY INVISIBLE (-3925 2600);
FORCEPROP 1 LASTPIN (-3975 2575) $PN 1
J 0
(-3965 2555);
DISPLAY 0.489362 (-3965 2555);
PAINT MONO (-3965 2555);
FORCEPROP 1 LASTPIN (-3975 2375) $PN 2
J 0
(-3965 2355);
DISPLAY 0.489362 (-3965 2355);
PAINT MONO (-3965 2355);
FORCEPROP 1 LAST MATERIAL X6S
J 0
(-3925 2375);
DISPLAY 0.489362 (-3925 2375);
PAINT SKYBLUE (-3925 2375);
FORCEPROP 1 LAST TOLERANCE 20%
J 0
(-3925 2425);
DISPLAY 0.489362 (-3925 2425);
PAINT SKYBLUE (-3925 2425);
FORCEPROP 1 LAST VOLTAGE 16V
J 0
(-3925 2475);
DISPLAY 0.489362 (-3925 2475);
PAINT SKYBLUE (-3925 2475);
FORCEPROP 1 LAST VALUE 22UF
J 0
(-3925 2525);
DISPLAY 0.489362 (-3925 2525);
PAINT SKYBLUE (-3925 2525);
FORCEPROP 1 LAST PACK_TYPE C0805
J 0
(-3925 2275);
DISPLAY 0.489362 (-3925 2275);
PAINT SKYBLUE (-3925 2275);
FORCEPROP 2 LAST CDS_LIB pure_quanta
J 0
(-3975 2475);
DISPLAY INVISIBLE (-3975 2475);
FORCEPROP 1 LAST PATH I25
J 0
(-3925 2625);
DISPLAY 0.978723 (-3925 2625);
PAINT WHITE (-3925 2625);
DISPLAY INVISIBLE (-3925 2625);
FORCEPROP 1 LAST PART_NUMBER CH6223MEA01
J 0
(-3925 2325);
DISPLAY 0.489362 (-3925 2325);
PAINT SKYBLUE (-3925 2325);
DISPLAY INVISIBLE (-3925 2325);
FORCEADD UNIVERSAL_GND..1
(-4250 3950);
FORCEPROP 3 LASTPIN (-4250 4000) SIG_NAME GND\g
J 0
(-4240 4010);
DISPLAY 0.659574 (-4240 4010);
PAINT MONO (-4240 4010);
DISPLAY INVISIBLE (-4240 4010);
FORCEPROP 2 LAST CDS_LIB pure_quanta_power
J 0
(-4250 3950);
DISPLAY INVISIBLE (-4250 3950);
FORCEPROP 1 LAST HDL_POWER GND
J 1
(-4225 3875);
DISPLAY 0.872340 (-4225 3875);
PAINT GREEN (-4225 3875);
DISPLAY INVISIBLE (-4225 3875);
FORCEPROP 1 LAST PATH I26
J 0
(-4175 3950);
DISPLAY 0.872340 (-4175 3950);
PAINT AQUA (-4175 3950);
DISPLAY INVISIBLE (-4175 3950);
FORCEADD Q_RES..1
(-3975 3775);
FORCEPROP 1 LAST LOCATION PR199
J 0
(-4000 3825);
DISPLAY 0.489362 (-4000 3825);
PAINT SKYBLUE (-4000 3825);
FORCEPROP 0 LAST $SEC 1
J 0
(-3975 3850);
DISPLAY 0.680851 (-3975 3850);
PAINT MONO (-3975 3850);
DISPLAY INVISIBLE (-3975 3850);
FORCEPROP 0 LAST CDS_SEC 1
J 0
(-3975 3850);
DISPLAY 1.021277 (-3975 3850);
DISPLAY INVISIBLE (-3975 3850);
FORCEPROP 1 LASTPIN (-4075 3775) $PN 1
J 0
(-4063 3787);
DISPLAY 0.489362 (-4063 3787);
PAINT MONO (-4063 3787);
FORCEPROP 1 LASTPIN (-3875 3775) $PN 2
J 0
(-3913 3787);
DISPLAY 0.489362 (-3913 3787);
PAINT MONO (-3913 3787);
FORCEPROP 1 LAST WATTAGE 1/16W
J 0
(-3875 3725);
DISPLAY 0.489362 (-3875 3725);
PAINT SKYBLUE (-3875 3725);
FORCEPROP 1 LAST MATERIAL CHIP
J 0
(-4225 3675);
DISPLAY 0.489362 (-4225 3675);
PAINT SKYBLUE (-4225 3675);
FORCEPROP 1 LAST TOLERANCE 5%
J 0
(-3850 3800);
DISPLAY 0.489362 (-3850 3800);
PAINT SKYBLUE (-3850 3800);
FORCEPROP 1 LAST VALUE 0
J 2
(-4100 3800);
DISPLAY 0.489362 (-4100 3800);
PAINT SKYBLUE (-4100 3800);
FORCEPROP 1 LAST PACK_TYPE 0402LF
J 0
(-3875 3675);
DISPLAY 0.489362 (-3875 3675);
PAINT SKYBLUE (-3875 3675);
FORCEPROP 2 LAST CDS_LIB pure_quanta
J 0
(-3975 3775);
DISPLAY INVISIBLE (-3975 3775);
FORCEPROP 1 LAST PATH I27
J 0
(-4025 3925);
DISPLAY 0.978723 (-4025 3925);
PAINT WHITE (-4025 3925);
DISPLAY INVISIBLE (-4025 3925);
FORCEPROP 1 LAST PART_NUMBER CS00002JB13
J 0
(-4225 3725);
DISPLAY 0.489362 (-4225 3725);
PAINT SKYBLUE (-4225 3725);
DISPLAY INVISIBLE (-4225 3725);
FORCEADD Q_CAP..1
(-7575 4600);
FORCEPROP 1 LAST LOCATION PC284_3
J 0
(-7525 4700);
DISPLAY 0.489362 (-7525 4700);
PAINT SKYBLUE (-7525 4700);
FORCEPROP 0 LAST $SEC 1
J 0
(-7525 4725);
DISPLAY 0.680851 (-7525 4725);
PAINT MONO (-7525 4725);
DISPLAY INVISIBLE (-7525 4725);
FORCEPROP 0 LAST CDS_SEC 1
J 0
(-7525 4725);
DISPLAY 1.021277 (-7525 4725);
DISPLAY INVISIBLE (-7525 4725);
FORCEPROP 1 LASTPIN (-7575 4700) $PN 1
J 0
(-7565 4680);
DISPLAY 0.489362 (-7565 4680);
PAINT MONO (-7565 4680);
FORCEPROP 1 LASTPIN (-7575 4500) $PN 2
J 0
(-7565 4480);
DISPLAY 0.489362 (-7565 4480);
PAINT MONO (-7565 4480);
FORCEPROP 1 LAST VOLTAGE 25V
J 0
(-7525 4600);
DISPLAY 0.489362 (-7525 4600);
PAINT SKYBLUE (-7525 4600);
FORCEPROP 1 LAST VALUE 0.1UF
J 0
(-7525 4650);
DISPLAY 0.489362 (-7525 4650);
PAINT SKYBLUE (-7525 4650);
FORCEPROP 1 LAST TOLERANCE 10%
J 0
(-7525 4550);
DISPLAY 0.489362 (-7525 4550);
PAINT SKYBLUE (-7525 4550);
FORCEPROP 1 LAST MATERIAL X7R
J 0
(-7525 4500);
DISPLAY 0.489362 (-7525 4500);
PAINT SKYBLUE (-7525 4500);
FORCEPROP 1 LAST PACK_TYPE 0402
J 0
(-7525 4400);
DISPLAY 0.489362 (-7525 4400);
PAINT SKYBLUE (-7525 4400);
FORCEPROP 2 LAST CDS_LIB pure_quanta
J 0
(-7575 4600);
DISPLAY INVISIBLE (-7575 4600);
FORCEPROP 1 LAST PATH I28
J 0
(-7525 4750);
DISPLAY 0.978723 (-7525 4750);
PAINT WHITE (-7525 4750);
DISPLAY INVISIBLE (-7525 4750);
FORCEPROP 1 LAST PART_NUMBER CH4104K1B00
J 0
(-7525 4450);
DISPLAY 0.489362 (-7525 4450);
PAINT SKYBLUE (-7525 4450);
DISPLAY INVISIBLE (-7525 4450);
FORCEADD UNIVERSAL_GND..1
(-7575 4325);
FORCEPROP 3 LASTPIN (-7575 4375) SIG_NAME GND\g
J 0
(-7565 4385);
DISPLAY 0.659574 (-7565 4385);
PAINT MONO (-7565 4385);
DISPLAY INVISIBLE (-7565 4385);
FORCEPROP 2 LAST CDS_LIB pure_quanta_power
J 0
(-7575 4325);
DISPLAY INVISIBLE (-7575 4325);
FORCEPROP 1 LAST HDL_POWER GND
J 1
(-7550 4250);
DISPLAY 0.872340 (-7550 4250);
PAINT GREEN (-7550 4250);
DISPLAY INVISIBLE (-7550 4250);
FORCEPROP 1 LAST PATH I29
J 0
(-7500 4325);
DISPLAY 0.872340 (-7500 4325);
PAINT AQUA (-7500 4325);
DISPLAY INVISIBLE (-7500 4325);
FORCEADD UNIVERSAL_GND..1
(-7500 1025);
FORCEPROP 3 LASTPIN (-7500 1075) SIG_NAME GND\g
J 0
(-7490 1085);
DISPLAY 0.659574 (-7490 1085);
PAINT MONO (-7490 1085);
DISPLAY INVISIBLE (-7490 1085);
FORCEPROP 2 LAST CDS_LIB pure_quanta_power
J 0
(-7500 1025);
DISPLAY INVISIBLE (-7500 1025);
FORCEPROP 1 LAST HDL_POWER GND
J 1
(-7475 950);
DISPLAY 0.872340 (-7475 950);
PAINT GREEN (-7475 950);
DISPLAY INVISIBLE (-7475 950);
FORCEPROP 1 LAST PATH I3
J 0
(-7425 1025);
DISPLAY 0.872340 (-7425 1025);
PAINT AQUA (-7425 1025);
DISPLAY INVISIBLE (-7425 1025);
FORCEADD OFFPAGE..1
(-7800 4775);
FORCEPROP 2 LAST $XR5 216 
J 0
(-8682 4775);
DISPLAY 0.638298 (-8682 4775);
PAINT MONO (-8682 4775);
FORCEPROP 2 LAST $XR4 215 
J 0
(-8562 4775);
DISPLAY 0.638298 (-8562 4775);
PAINT MONO (-8562 4775);
FORCEPROP 2 LAST $XR3 213 
J 0
(-8442 4775);
DISPLAY 0.638298 (-8442 4775);
PAINT MONO (-8442 4775);
FORCEPROP 2 LAST $XR2 212 
J 0
(-8322 4775);
DISPLAY 0.638298 (-8322 4775);
PAINT MONO (-8322 4775);
FORCEPROP 2 LAST $XR1 211 
J 0
(-8202 4775);
DISPLAY 0.638298 (-8202 4775);
PAINT MONO (-8202 4775);
FORCEPROP 2 LAST $XR0 210 
J 0
(-8082 4775);
DISPLAY 0.638298 (-8082 4775);
PAINT MONO (-8082 4775);
FORCEPROP 2 LAST CDS_LIB standard
J 0
(-7800 4775);
DISPLAY INVISIBLE (-7800 4775);
FORCEPROP 1 LAST OFFPAGE TRUE
J 0
(-7475 4650);
DISPLAY 0.872340 (-7475 4650);
PAINT GREEN (-7475 4650);
DISPLAY INVISIBLE (-7475 4650);
FORCEPROP 1 LAST COMMENT_BODY TRUE
J 0
(-7675 4675);
DISPLAY 0.872340 (-7675 4675);
PAINT GREEN (-7675 4675);
DISPLAY INVISIBLE (-7675 4675);
FORCEPROP 2 LAST PATH I30
J 0
(-8050 4825);
DISPLAY 0.680851 (-8050 4825);
DISPLAY INVISIBLE (-8050 4825);
FORCEADD UNIVERSAL_GND..1
(-7275 4400);
FORCEPROP 3 LASTPIN (-7275 4450) SIG_NAME GND\g
J 0
(-7265 4460);
DISPLAY 0.659574 (-7265 4460);
PAINT MONO (-7265 4460);
DISPLAY INVISIBLE (-7265 4460);
FORCEPROP 2 LAST CDS_LIB pure_quanta_power
J 0
(-7275 4400);
DISPLAY INVISIBLE (-7275 4400);
FORCEPROP 1 LAST HDL_POWER GND
J 1
(-7250 4325);
DISPLAY 0.872340 (-7250 4325);
PAINT GREEN (-7250 4325);
DISPLAY INVISIBLE (-7250 4325);
FORCEPROP 1 LAST PATH I31
J 0
(-7200 4400);
DISPLAY 0.872340 (-7200 4400);
PAINT AQUA (-7200 4400);
DISPLAY INVISIBLE (-7200 4400);
FORCEADD OFFPAGE..1
(-6850 4275);
FORCEPROP 2 LAST $XR0 210 
J 0
(-7102 4275);
DISPLAY 0.638298 (-7102 4275);
PAINT MONO (-7102 4275);
FORCEPROP 2 LAST CDS_LIB standard
J 2
(-6850 4275);
DISPLAY INVISIBLE (-6850 4275);
FORCEPROP 1 LAST OFFPAGE TRUE
J 0
(-6525 4150);
DISPLAY 0.872340 (-6525 4150);
PAINT GREEN (-6525 4150);
DISPLAY INVISIBLE (-6525 4150);
FORCEPROP 1 LAST COMMENT_BODY TRUE
J 0
(-6725 4175);
DISPLAY 0.872340 (-6725 4175);
PAINT GREEN (-6725 4175);
DISPLAY INVISIBLE (-6725 4175);
FORCEPROP 2 LAST PATH I32
J 0
(-7100 4325);
DISPLAY 0.680851 (-7100 4325);
DISPLAY INVISIBLE (-7100 4325);
FORCEADD OFFPAGE..2
R 2
(-6875 4375);
FORCEPROP 2 LAST $XR3 210 
J 0
(-7250 4339);
DISPLAY 0.638298 (-7250 4339);
PAINT MONO (-7250 4339);
FORCEPROP 2 LAST $XR2 213 
J 0
(-7130 4339);
DISPLAY 0.638298 (-7130 4339);
PAINT MONO (-7130 4339);
FORCEPROP 2 LAST $XR1 212 
J 0
(-7250 4375);
DISPLAY 0.638298 (-7250 4375);
PAINT MONO (-7250 4375);
FORCEPROP 2 LAST $XR0 211 
J 0
(-7130 4375);
DISPLAY 0.638298 (-7130 4375);
PAINT MONO (-7130 4375);
FORCEPROP 2 LAST CDS_LIB standard
J 0
(-6875 4375);
DISPLAY INVISIBLE (-6875 4375);
FORCEPROP 1 LAST OFFPAGE TRUE
J 2
(-7200 4250);
DISPLAY 0.872340 (-7200 4250);
PAINT GREEN (-7200 4250);
DISPLAY INVISIBLE (-7200 4250);
FORCEPROP 1 LAST COMMENT_BODY TRUE
J 2
(-6830 4280);
DISPLAY 0.872340 (-6830 4280);
PAINT GREEN (-6830 4280);
DISPLAY INVISIBLE (-6830 4280);
FORCEPROP 2 LAST PATH I33
J 0
(-7150 4425);
DISPLAY 0.680851 (-7150 4425);
DISPLAY INVISIBLE (-7150 4425);
FORCEADD Q_RES..1
(-6950 4575);
FORCEPROP 1 LAST LOCATION PR195
J 0
(-7000 4625);
DISPLAY 0.489362 (-7000 4625);
PAINT SKYBLUE (-7000 4625);
FORCEPROP 0 LAST $SEC 1
J 0
(-6950 4650);
DISPLAY 0.680851 (-6950 4650);
PAINT MONO (-6950 4650);
DISPLAY INVISIBLE (-6950 4650);
FORCEPROP 0 LAST CDS_SEC 1
J 0
(-6950 4650);
DISPLAY 1.021277 (-6950 4650);
DISPLAY INVISIBLE (-6950 4650);
FORCEPROP 1 LASTPIN (-7050 4575) $PN 1
J 0
(-7038 4587);
DISPLAY 0.489362 (-7038 4587);
PAINT MONO (-7038 4587);
FORCEPROP 1 LASTPIN (-6850 4575) $PN 2
J 0
(-6888 4587);
DISPLAY 0.489362 (-6888 4587);
PAINT MONO (-6888 4587);
FORCEPROP 1 LAST MATERIAL EMPTY
J 0
(-7250 4475);
DISPLAY 0.489362 (-7250 4475);
PAINT RED (-7250 4475);
FORCEPROP 1 LAST PACK_TYPE 0402LF
J 0
(-6850 4525);
DISPLAY 0.489362 (-6850 4525);
PAINT SKYBLUE (-6850 4525);
FORCEPROP 1 LAST WATTAGE 1/16W
J 0
(-6850 4475);
DISPLAY 0.489362 (-6850 4475);
PAINT SKYBLUE (-6850 4475);
FORCEPROP 1 LAST TOLERANCE 1%
J 0
(-6825 4600);
DISPLAY 0.489362 (-6825 4600);
PAINT SKYBLUE (-6825 4600);
FORCEPROP 1 LAST VALUE 8.87K
J 2
(-7075 4600);
DISPLAY 0.489362 (-7075 4600);
PAINT SKYBLUE (-7075 4600);
FORCEPROP 2 LAST CDS_LIB pure_quanta
J 0
(-6950 4575);
DISPLAY INVISIBLE (-6950 4575);
FORCEPROP 1 LAST PATH I34
J 0
(-7000 4725);
DISPLAY 0.978723 (-7000 4725);
PAINT WHITE (-7000 4725);
DISPLAY INVISIBLE (-7000 4725);
FORCEPROP 1 LAST PART_NUMBER CS28872FB01
J 0
(-7250 4525);
DISPLAY 0.489362 (-7250 4525);
PAINT SKYBLUE (-7250 4525);
DISPLAY INVISIBLE (-7250 4525);
FORCEADD UNIVERSAL_GND..1
(-7250 5025);
FORCEPROP 3 LASTPIN (-7250 5075) SIG_NAME GND\g
J 0
(-7240 5085);
DISPLAY 0.659574 (-7240 5085);
PAINT MONO (-7240 5085);
DISPLAY INVISIBLE (-7240 5085);
FORCEPROP 2 LAST CDS_LIB pure_quanta_power
J 0
(-7250 5025);
DISPLAY INVISIBLE (-7250 5025);
FORCEPROP 1 LAST HDL_POWER GND
J 1
(-7225 4950);
DISPLAY 0.872340 (-7225 4950);
PAINT GREEN (-7225 4950);
DISPLAY INVISIBLE (-7225 4950);
FORCEPROP 1 LAST PATH I35
J 0
(-7175 5025);
DISPLAY 0.872340 (-7175 5025);
PAINT AQUA (-7175 5025);
DISPLAY INVISIBLE (-7175 5025);
FORCEADD OFFPAGE..2
R 2
(-6900 4875);
FORCEPROP 2 LAST $XR0 210 
J 0
(-7155 4875);
DISPLAY 0.638298 (-7155 4875);
PAINT MONO (-7155 4875);
FORCEPROP 2 LAST CDS_LIB standard
J 2
(-6900 4875);
DISPLAY INVISIBLE (-6900 4875);
FORCEPROP 1 LAST OFFPAGE TRUE
J 2
(-7225 4750);
DISPLAY 0.872340 (-7225 4750);
PAINT GREEN (-7225 4750);
DISPLAY INVISIBLE (-7225 4750);
FORCEPROP 1 LAST COMMENT_BODY TRUE
J 2
(-6855 4780);
DISPLAY 0.872340 (-6855 4780);
PAINT GREEN (-6855 4780);
DISPLAY INVISIBLE (-6855 4780);
FORCEPROP 2 LAST PATH I36
J 0
(-7150 4925);
DISPLAY 0.680851 (-7150 4925);
DISPLAY INVISIBLE (-7150 4925);
FORCEADD Q_CAP..1
(-7250 5225);
FORCEPROP 1 LAST LOCATION PC286
J 0
(-7200 5325);
DISPLAY 0.489362 (-7200 5325);
PAINT SKYBLUE (-7200 5325);
FORCEPROP 0 LAST $SEC 1
J 0
(-7200 5375);
DISPLAY 0.680851 (-7200 5375);
PAINT MONO (-7200 5375);
DISPLAY INVISIBLE (-7200 5375);
FORCEPROP 0 LAST CDS_SEC 1
J 0
(-7200 5375);
DISPLAY 1.021277 (-7200 5375);
DISPLAY INVISIBLE (-7200 5375);
FORCEPROP 1 LASTPIN (-7250 5325) $PN 1
J 0
(-7240 5305);
DISPLAY 0.489362 (-7240 5305);
PAINT MONO (-7240 5305);
FORCEPROP 1 LASTPIN (-7250 5125) $PN 2
J 0
(-7240 5105);
DISPLAY 0.489362 (-7240 5105);
PAINT MONO (-7240 5105);
FORCEPROP 1 LAST VOLTAGE 10V
J 0
(-7200 5225);
DISPLAY 0.489362 (-7200 5225);
PAINT SKYBLUE (-7200 5225);
FORCEPROP 1 LAST VALUE 2.2UF
J 0
(-7200 5275);
DISPLAY 0.489362 (-7200 5275);
PAINT SKYBLUE (-7200 5275);
FORCEPROP 1 LAST TOLERANCE 10%
J 0
(-7200 5175);
DISPLAY 0.489362 (-7200 5175);
PAINT SKYBLUE (-7200 5175);
FORCEPROP 1 LAST MATERIAL X6S
J 0
(-7200 5125);
DISPLAY 0.489362 (-7200 5125);
PAINT SKYBLUE (-7200 5125);
FORCEPROP 1 LAST PACK_TYPE C0402
J 0
(-7200 5025);
DISPLAY 0.489362 (-7200 5025);
PAINT SKYBLUE (-7200 5025);
FORCEPROP 2 LAST CDS_LIB pure_quanta
J 0
(-7250 5225);
DISPLAY INVISIBLE (-7250 5225);
FORCEPROP 1 LAST PATH I37
J 0
(-7200 5375);
DISPLAY 0.978723 (-7200 5375);
PAINT WHITE (-7200 5375);
DISPLAY INVISIBLE (-7200 5375);
FORCEPROP 1 LAST PART_NUMBER CH5222KEB01
J 0
(-7200 5075);
DISPLAY 0.489362 (-7200 5075);
PAINT SKYBLUE (-7200 5075);
DISPLAY INVISIBLE (-7200 5075);
FORCEADD Q_RES..2
(-7250 5775);
FORCEPROP 1 LAST LOCATION PR193
J 0
(-7205 5900);
DISPLAY 0.489362 (-7205 5900);
PAINT SKYBLUE (-7205 5900);
FORCEPROP 0 LAST $SEC 1
J 0
(-7200 5950);
DISPLAY 0.680851 (-7200 5950);
PAINT MONO (-7200 5950);
DISPLAY INVISIBLE (-7200 5950);
FORCEPROP 0 LAST CDS_SEC 1
J 0
(-7200 5950);
DISPLAY 1.021277 (-7200 5950);
DISPLAY INVISIBLE (-7200 5950);
FORCEPROP 1 LASTPIN (-7250 5875) $PN 1
J 0
(-7245 5837);
DISPLAY 0.489362 (-7245 5837);
PAINT MONO (-7245 5837);
FORCEPROP 1 LASTPIN (-7250 5675) $PN 2
J 0
(-7245 5685);
DISPLAY 0.489362 (-7245 5685);
PAINT MONO (-7245 5685);
FORCEPROP 1 LAST MATERIAL CHIP
J 0
(-7200 5700);
DISPLAY 0.489362 (-7200 5700);
PAINT SKYBLUE (-7200 5700);
FORCEPROP 1 LAST TOLERANCE 1%
J 0
(-7200 5800);
DISPLAY 0.489362 (-7200 5800);
PAINT SKYBLUE (-7200 5800);
FORCEPROP 1 LAST PACK_TYPE 0402LF
J 0
(-7200 5600);
DISPLAY 0.489362 (-7200 5600);
PAINT SKYBLUE (-7200 5600);
FORCEPROP 1 LAST WATTAGE 1/16W
J 0
(-7200 5750);
DISPLAY 0.489362 (-7200 5750);
PAINT SKYBLUE (-7200 5750);
FORCEPROP 1 LAST VALUE 2.2
J 0
(-7200 5850);
DISPLAY 0.489362 (-7200 5850);
PAINT SKYBLUE (-7200 5850);
FORCEPROP 2 LAST CDS_LIB pure_quanta
J 0
(-7250 5775);
DISPLAY INVISIBLE (-7250 5775);
FORCEPROP 1 LAST PATH I38
J 0
(-7200 5950);
DISPLAY 0.978723 (-7200 5950);
PAINT WHITE (-7200 5950);
DISPLAY INVISIBLE (-7200 5950);
FORCEPROP 1 LAST PART_NUMBER CS-2202FB01
J 0
(-7200 5650);
DISPLAY 0.489362 (-7200 5650);
PAINT SKYBLUE (-7200 5650);
DISPLAY INVISIBLE (-7200 5650);
FORCEADD ISL99390FRZTR5935..1
(-5750 4875);
FORCEPROP 1 LAST LOCATION PU27
J 0
(-6050 5750);
DISPLAY 0.489362 (-6050 5750);
PAINT SKYBLUE (-6050 5750);
FORCEPROP 0 LAST $SEC 1
J 0
(-6050 5900);
DISPLAY 0.680851 (-6050 5900);
PAINT MONO (-6050 5900);
DISPLAY INVISIBLE (-6050 5900);
FORCEPROP 2 LAST CDS_SEC 1
J 0
(-6050 5900);
DISPLAY 1.021277 (-6050 5900);
DISPLAY INVISIBLE (-6050 5900);
FORCEPROP 0 LASTPIN (-5350 4425) $PN 2
J 0
(-5340 4435);
DISPLAY 0.489362 (-5340 4435);
PAINT MONO (-5340 4435);
FORCEPROP 0 LASTPIN (-5350 5225) $PN 33
J 0
(-5340 5235);
DISPLAY 0.489362 (-5340 5235);
PAINT MONO (-5340 5235);
FORCEPROP 0 LASTPIN (-6200 4625) $PN 31
J 2
(-6210 4635);
DISPLAY 0.489362 (-6210 4635);
PAINT MONO (-6210 4635);
FORCEPROP 0 LASTPIN (-6200 5025) $PN 35
J 2
(-6210 5035);
DISPLAY 0.489362 (-6210 5035);
PAINT MONO (-6210 5035);
FORCEPROP 0 LASTPIN (-5350 4575) $PN 6
J 0
(-5340 4585);
DISPLAY 0.489362 (-5340 4585);
PAINT MONO (-5340 4585);
FORCEPROP 0 LASTPIN (-5350 4525) $PN 41
J 0
(-5340 4535);
DISPLAY 0.489362 (-5340 4535);
PAINT MONO (-5340 4535);
FORCEPROP 0 LASTPIN (-6200 4875) $PN 38
J 2
(-6210 4885);
DISPLAY 0.489362 (-6210 4885);
PAINT MONO (-6210 4885);
FORCEPROP 0 LASTPIN (-6200 4575) $PN 37
J 2
(-6210 4585);
DISPLAY 0.489362 (-6210 4585);
PAINT MONO (-6210 4585);
FORCEPROP 0 LASTPIN (-5350 4375) $PN 5
J 0
(-5340 4385);
DISPLAY 0.489362 (-5340 4385);
PAINT MONO (-5340 4385);
FORCEPROP 0 LASTPIN (-5350 4325) $PN 7_9-20_24
J 0
(-5340 4335);
DISPLAY 0.489362 (-5340 4335);
PAINT MONO (-5340 4335);
FORCEPROP 0 LASTPIN (-5350 4275) $PN 40
J 0
(-5340 4285);
DISPLAY 0.489362 (-5340 4285);
PAINT MONO (-5340 4285);
FORCEPROP 0 LASTPIN (-5350 4975) $PN 32
J 0
(-5340 4985);
DISPLAY 0.489362 (-5340 4985);
PAINT MONO (-5340 4985);
FORCEPROP 0 LASTPIN (-6200 5525) $PN 4
J 2
(-6210 5535);
DISPLAY 0.489362 (-6210 5535);
PAINT MONO (-6210 5535);
FORCEPROP 0 LASTPIN (-6200 4275) $PN 34
J 2
(-6210 4285);
DISPLAY 0.489362 (-6210 4285);
PAINT MONO (-6210 4285);
FORCEPROP 0 LASTPIN (-6200 4775) $PN 39
J 2
(-6210 4785);
DISPLAY 0.489362 (-6210 4785);
PAINT MONO (-6210 4785);
FORCEPROP 0 LASTPIN (-5350 4875) $PN 10_19
J 0
(-5340 4885);
DISPLAY 0.489362 (-5340 4885);
PAINT MONO (-5340 4885);
FORCEPROP 0 LASTPIN (-6200 4375) $PN 36
J 2
(-6210 4385);
DISPLAY 0.489362 (-6210 4385);
PAINT MONO (-6210 4385);
FORCEPROP 0 LASTPIN (-6200 5225) $PN 3
J 2
(-6210 5235);
DISPLAY 0.489362 (-6210 5235);
PAINT MONO (-6210 5235);
FORCEPROP 0 LASTPIN (-5350 5525) $PN 25_29
J 0
(-5340 5535);
DISPLAY 0.489362 (-5340 5535);
PAINT MONO (-5340 5535);
FORCEPROP 0 LASTPIN (-5350 5475) $PN 30
J 0
(-5340 5485);
DISPLAY 0.489362 (-5340 5485);
PAINT MONO (-5340 5485);
FORCEPROP 0 LASTPIN (-5350 4625) $PN 1
J 0
(-5340 4635);
DISPLAY 0.489362 (-5340 4635);
PAINT MONO (-5340 4635);
FORCEPROP 2 LAST VALUE ISL99390FRZ-TR5935
J 0
(-6050 5800);
DISPLAY 0.489362 (-6050 5800);
PAINT SKYBLUE (-6050 5800);
FORCEPROP 1 LAST MATERIAL IC
J 0
(-6050 5600);
DISPLAY 0.489362 (-6050 5600);
PAINT SKYBLUE (-6050 5600);
FORCEPROP 2 LAST PART_TYPE SMLF
J 0
(-6050 5850);
DISPLAY 1.021277 (-6050 5850);
FORCEPROP 1 LAST CDS_LMAN_SYM_OUTLINE -300,700,250,-650
J 0
(-5750 4875);
DISPLAY 0.468085 (-5750 4875);
PAINT GREEN (-5750 4875);
DISPLAY INVISIBLE (-5750 4875);
FORCEPROP 1 LAST NEEDS_NO_SIZE TRUE
J 0
(-5750 4875);
DISPLAY 0.723404 (-5750 4875);
PAINT GREEN (-5750 4875);
DISPLAY INVISIBLE (-5750 4875);
FORCEPROP 2 LAST CDS_LIB pure_quanta
J 0
(-5750 4875);
DISPLAY INVISIBLE (-5750 4875);
FORCEPROP 1 LAST PATH I39
J 0
(-5750 4875);
DISPLAY 0.723404 (-5750 4875);
PAINT GREEN (-5750 4875);
DISPLAY INVISIBLE (-5750 4875);
FORCEPROP 1 LAST PART_NUMBER AL099390004
J 0
(-6050 5675);
DISPLAY 0.489362 (-6050 5675);
PAINT SKYBLUE (-6050 5675);
DISPLAY INVISIBLE (-6050 5675);
FORCEADD UNIVERSAL_GND..1
(-7175 1100);
FORCEPROP 3 LASTPIN (-7175 1150) SIG_NAME GND\g
J 0
(-7165 1160);
DISPLAY 0.659574 (-7165 1160);
PAINT MONO (-7165 1160);
DISPLAY INVISIBLE (-7165 1160);
FORCEPROP 2 LAST CDS_LIB pure_quanta_power
J 0
(-7175 1100);
DISPLAY INVISIBLE (-7175 1100);
FORCEPROP 1 LAST HDL_POWER GND
J 1
(-7150 1025);
DISPLAY 0.872340 (-7150 1025);
PAINT GREEN (-7150 1025);
DISPLAY INVISIBLE (-7150 1025);
FORCEPROP 1 LAST PATH I4
J 0
(-7100 1100);
DISPLAY 0.872340 (-7100 1100);
PAINT AQUA (-7100 1100);
DISPLAY INVISIBLE (-7100 1100);
FORCEADD UNIVERSAL_GND..1
(-6900 5525);
FORCEPROP 3 LASTPIN (-6900 5575) SIG_NAME GND\g
J 0
(-6890 5585);
DISPLAY 0.659574 (-6890 5585);
PAINT MONO (-6890 5585);
DISPLAY INVISIBLE (-6890 5585);
FORCEPROP 2 LAST CDS_LIB pure_quanta_power
J 0
(-6900 5525);
DISPLAY INVISIBLE (-6900 5525);
FORCEPROP 1 LAST HDL_POWER GND
J 1
(-6875 5450);
DISPLAY 0.872340 (-6875 5450);
PAINT GREEN (-6875 5450);
DISPLAY INVISIBLE (-6875 5450);
FORCEPROP 1 LAST PATH I40
J 0
(-6825 5525);
DISPLAY 0.872340 (-6825 5525);
PAINT AQUA (-6825 5525);
DISPLAY INVISIBLE (-6825 5525);
FORCEADD Q_CAP..1
(-6900 5800);
FORCEPROP 1 LAST LOCATION PC288_C0P1_3
J 0
(-6850 5900);
DISPLAY 0.489362 (-6850 5900);
PAINT SKYBLUE (-6850 5900);
FORCEPROP 0 LAST $SEC 1
J 0
(-6850 5950);
DISPLAY 0.680851 (-6850 5950);
PAINT MONO (-6850 5950);
DISPLAY INVISIBLE (-6850 5950);
FORCEPROP 0 LAST CDS_SEC 1
J 0
(-6850 5950);
DISPLAY 1.021277 (-6850 5950);
DISPLAY INVISIBLE (-6850 5950);
FORCEPROP 1 LASTPIN (-6900 5900) $PN 1
J 0
(-6890 5880);
DISPLAY 0.489362 (-6890 5880);
PAINT MONO (-6890 5880);
FORCEPROP 1 LASTPIN (-6900 5700) $PN 2
J 0
(-6890 5680);
DISPLAY 0.489362 (-6890 5680);
PAINT MONO (-6890 5680);
FORCEPROP 1 LAST TOLERANCE 10%
J 0
(-6850 5750);
DISPLAY 0.489362 (-6850 5750);
PAINT SKYBLUE (-6850 5750);
FORCEPROP 1 LAST MATERIAL X6S
J 0
(-6850 5700);
DISPLAY 0.489362 (-6850 5700);
PAINT SKYBLUE (-6850 5700);
FORCEPROP 1 LAST VOLTAGE 10V
J 0
(-6850 5800);
DISPLAY 0.489362 (-6850 5800);
PAINT SKYBLUE (-6850 5800);
FORCEPROP 1 LAST PACK_TYPE C0402
J 0
(-6850 5600);
DISPLAY 0.489362 (-6850 5600);
PAINT SKYBLUE (-6850 5600);
FORCEPROP 1 LAST VALUE 2.2UF
J 0
(-6850 5850);
DISPLAY 0.489362 (-6850 5850);
PAINT SKYBLUE (-6850 5850);
FORCEPROP 2 LAST CDS_LIB pure_quanta
J 0
(-6900 5800);
DISPLAY INVISIBLE (-6900 5800);
FORCEPROP 1 LAST PATH I41
J 0
(-6850 5950);
DISPLAY 0.978723 (-6850 5950);
PAINT WHITE (-6850 5950);
DISPLAY INVISIBLE (-6850 5950);
FORCEPROP 1 LAST PART_NUMBER CH5222KEB01
J 0
(-6850 5650);
DISPLAY 0.489362 (-6850 5650);
PAINT SKYBLUE (-6850 5650);
DISPLAY INVISIBLE (-6850 5650);
FORCEADD VCC_CORE..1
(-7250 6175);
FORCEPROP 3 LASTPIN (-7250 6125) SIG_NAME PVDDCR_CPU0_P1_PVCC\g
J 0
(-7240 6135);
DISPLAY 0.659574 (-7240 6135);
PAINT MONO (-7240 6135);
DISPLAY INVISIBLE (-7240 6135);
FORCEPROP 1 LAST HDL_POWER PVDDCR_CPU0_P1_PVCC
J 1
(-7250 6225);
DISPLAY 0.489362 (-7250 6225);
PAINT GREEN (-7250 6225);
FORCEPROP 2 LAST CDS_LIB pure_quanta_power
J 0
(-7250 6175);
DISPLAY INVISIBLE (-7250 6175);
FORCEPROP 1 LAST PATH I42
J 0
(-7200 6200);
DISPLAY 0.872340 (-7200 6200);
PAINT AQUA (-7200 6200);
DISPLAY INVISIBLE (-7200 6200);
FORCEADD UNIVERSAL_GND..1
(-5200 4100);
FORCEPROP 3 LASTPIN (-5200 4150) SIG_NAME GND\g
J 0
(-5190 4160);
DISPLAY 0.659574 (-5190 4160);
PAINT MONO (-5190 4160);
DISPLAY INVISIBLE (-5190 4160);
FORCEPROP 2 LAST CDS_LIB pure_quanta_power
J 0
(-5200 4100);
DISPLAY INVISIBLE (-5200 4100);
FORCEPROP 1 LAST HDL_POWER GND
J 1
(-5175 4025);
DISPLAY 0.872340 (-5175 4025);
PAINT GREEN (-5175 4025);
DISPLAY INVISIBLE (-5175 4025);
FORCEPROP 1 LAST PATH I43
J 0
(-5125 4100);
DISPLAY 0.872340 (-5125 4100);
PAINT AQUA (-5125 4100);
DISPLAY INVISIBLE (-5125 4100);
FORCEADD Q_CAP..1
(-5125 5775);
FORCEPROP 1 LAST LOCATION PC290_3
J 0
(-5075 5875);
DISPLAY 0.489362 (-5075 5875);
PAINT SKYBLUE (-5075 5875);
FORCEPROP 0 LAST $SEC 1
J 0
(-5075 5925);
DISPLAY 0.680851 (-5075 5925);
PAINT MONO (-5075 5925);
DISPLAY INVISIBLE (-5075 5925);
FORCEPROP 0 LAST CDS_SEC 1
J 0
(-5075 5925);
DISPLAY 1.021277 (-5075 5925);
DISPLAY INVISIBLE (-5075 5925);
FORCEPROP 1 LASTPIN (-5125 5875) $PN 1
J 0
(-5115 5855);
DISPLAY 0.489362 (-5115 5855);
PAINT MONO (-5115 5855);
FORCEPROP 1 LASTPIN (-5125 5675) $PN 2
J 0
(-5115 5655);
DISPLAY 0.489362 (-5115 5655);
PAINT MONO (-5115 5655);
FORCEPROP 1 LAST PACK_TYPE 0402
J 0
(-5075 5575);
DISPLAY 0.489362 (-5075 5575);
PAINT SKYBLUE (-5075 5575);
FORCEPROP 1 LAST VOLTAGE 25V
J 0
(-5075 5775);
DISPLAY 0.489362 (-5075 5775);
PAINT SKYBLUE (-5075 5775);
FORCEPROP 1 LAST VALUE 0.1UF
J 0
(-5075 5825);
DISPLAY 0.489362 (-5075 5825);
PAINT SKYBLUE (-5075 5825);
FORCEPROP 1 LAST TOLERANCE 10%
J 0
(-5075 5725);
DISPLAY 0.489362 (-5075 5725);
PAINT SKYBLUE (-5075 5725);
FORCEPROP 1 LAST MATERIAL X7R
J 0
(-5075 5675);
DISPLAY 0.489362 (-5075 5675);
PAINT SKYBLUE (-5075 5675);
FORCEPROP 2 LAST CDS_LIB pure_quanta
J 0
(-5125 5775);
DISPLAY INVISIBLE (-5125 5775);
FORCEPROP 1 LAST PATH I44
J 0
(-5075 5925);
DISPLAY 0.978723 (-5075 5925);
PAINT WHITE (-5075 5925);
DISPLAY INVISIBLE (-5075 5925);
FORCEPROP 1 LAST PART_NUMBER CH4104K1B00
J 0
(-5075 5625);
DISPLAY 0.489362 (-5075 5625);
PAINT SKYBLUE (-5075 5625);
DISPLAY INVISIBLE (-5075 5625);
FORCEADD Q_RES..2
(-4250 4175);
FORCEPROP 1 LAST LOCATION PR522
J 0
(-4205 4300);
DISPLAY 0.489362 (-4205 4300);
PAINT SKYBLUE (-4205 4300);
FORCEPROP 0 LAST $SEC 1
J 0
(-4200 4350);
DISPLAY 0.680851 (-4200 4350);
PAINT MONO (-4200 4350);
DISPLAY INVISIBLE (-4200 4350);
FORCEPROP 0 LAST CDS_SEC 1
J 0
(-4200 4350);
DISPLAY 1.021277 (-4200 4350);
DISPLAY INVISIBLE (-4200 4350);
FORCEPROP 1 LASTPIN (-4250 4275) $PN 1
J 0
(-4245 4237);
DISPLAY 0.489362 (-4245 4237);
PAINT MONO (-4245 4237);
FORCEPROP 1 LASTPIN (-4250 4075) $PN 2
J 0
(-4245 4085);
DISPLAY 0.489362 (-4245 4085);
PAINT MONO (-4245 4085);
FORCEPROP 1 LAST PACK_TYPE 0402LF
J 0
(-4210 4000);
DISPLAY 0.489362 (-4210 4000);
PAINT SKYBLUE (-4210 4000);
FORCEPROP 1 LAST VALUE 1.5
J 0
(-4205 4250);
DISPLAY 0.489362 (-4205 4250);
PAINT SKYBLUE (-4205 4250);
FORCEPROP 1 LAST TOLERANCE 1%
J 0
(-4205 4200);
DISPLAY 0.489362 (-4205 4200);
PAINT SKYBLUE (-4205 4200);
FORCEPROP 1 LAST MATERIAL EMPTY
J 0
(-4210 4100);
DISPLAY 0.489362 (-4210 4100);
PAINT RED (-4210 4100);
FORCEPROP 1 LAST WATTAGE 1/8W
J 0
(-4210 4150);
DISPLAY 0.489362 (-4210 4150);
PAINT SKYBLUE (-4210 4150);
FORCEPROP 2 LAST CDS_LIB pure_quanta
J 0
(-4250 4175);
DISPLAY INVISIBLE (-4250 4175);
FORCEPROP 1 LAST PATH I45
J 0
(-4200 4350);
DISPLAY 0.978723 (-4200 4350);
PAINT WHITE (-4200 4350);
DISPLAY INVISIBLE (-4200 4350);
FORCEPROP 1 LAST PART_NUMBER CS-1504FB00
J 0
(-4210 4050);
DISPLAY 0.489362 (-4210 4050);
PAINT SKYBLUE (-4210 4050);
DISPLAY INVISIBLE (-4210 4050);
FORCEADD Q_CAP..1
(-4250 4675);
FORCEPROP 1 LAST LOCATION PC316
J 0
(-4200 4775);
DISPLAY 0.489362 (-4200 4775);
PAINT SKYBLUE (-4200 4775);
FORCEPROP 0 LAST $SEC 1
J 0
(-4200 4825);
DISPLAY 0.680851 (-4200 4825);
PAINT MONO (-4200 4825);
DISPLAY INVISIBLE (-4200 4825);
FORCEPROP 0 LAST CDS_SEC 1
J 0
(-4200 4825);
DISPLAY 1.021277 (-4200 4825);
DISPLAY INVISIBLE (-4200 4825);
FORCEPROP 1 LASTPIN (-4250 4775) $PN 1
J 0
(-4240 4755);
DISPLAY 0.489362 (-4240 4755);
PAINT MONO (-4240 4755);
FORCEPROP 1 LASTPIN (-4250 4575) $PN 2
J 0
(-4240 4555);
DISPLAY 0.489362 (-4240 4555);
PAINT MONO (-4240 4555);
FORCEPROP 1 LAST PACK_TYPE C0402
J 0
(-4200 4475);
DISPLAY 0.489362 (-4200 4475);
PAINT SKYBLUE (-4200 4475);
FORCEPROP 1 LAST VOLTAGE 50V
J 0
(-4200 4675);
DISPLAY 0.489362 (-4200 4675);
PAINT SKYBLUE (-4200 4675);
FORCEPROP 1 LAST VALUE 560PF
J 0
(-4200 4725);
DISPLAY 0.489362 (-4200 4725);
PAINT SKYBLUE (-4200 4725);
FORCEPROP 1 LAST TOLERANCE 10%
J 0
(-4200 4625);
DISPLAY 0.489362 (-4200 4625);
PAINT SKYBLUE (-4200 4625);
FORCEPROP 1 LAST MATERIAL EMPTY
J 0
(-4200 4575);
DISPLAY 0.489362 (-4200 4575);
PAINT RED (-4200 4575);
FORCEPROP 2 LAST CDS_LIB pure_quanta
J 0
(-4250 4675);
DISPLAY INVISIBLE (-4250 4675);
FORCEPROP 1 LAST PATH I46
J 0
(-4200 4825);
DISPLAY 0.978723 (-4200 4825);
PAINT WHITE (-4200 4825);
DISPLAY INVISIBLE (-4200 4825);
FORCEPROP 1 LAST PART_NUMBER CH1566K1B09
J 0
(-4200 4525);
DISPLAY 0.489362 (-4200 4525);
PAINT SKYBLUE (-4200 4525);
DISPLAY INVISIBLE (-4200 4525);
FORCEADD Q_RES..1
(-4375 5225);
FORCEPROP 1 LAST LOCATION PR197
J 0
(-4425 5275);
DISPLAY 0.489362 (-4425 5275);
PAINT SKYBLUE (-4425 5275);
FORCEPROP 0 LAST $SEC 1
J 0
(-4350 5300);
DISPLAY 0.680851 (-4350 5300);
PAINT MONO (-4350 5300);
DISPLAY INVISIBLE (-4350 5300);
FORCEPROP 0 LAST CDS_SEC 1
J 0
(-4350 5300);
DISPLAY 1.021277 (-4350 5300);
DISPLAY INVISIBLE (-4350 5300);
FORCEPROP 1 LASTPIN (-4475 5225) $PN 1
J 0
(-4463 5237);
DISPLAY 0.489362 (-4463 5237);
PAINT MONO (-4463 5237);
FORCEPROP 1 LASTPIN (-4275 5225) $PN 2
J 0
(-4313 5237);
DISPLAY 0.489362 (-4313 5237);
PAINT MONO (-4313 5237);
FORCEPROP 1 LAST MATERIAL CHIP
J 0
(-4625 5125);
DISPLAY 0.489362 (-4625 5125);
PAINT SKYBLUE (-4625 5125);
FORCEPROP 1 LAST TOLERANCE 1%
J 0
(-4250 5250);
DISPLAY 0.489362 (-4250 5250);
PAINT SKYBLUE (-4250 5250);
FORCEPROP 1 LAST VALUE 5.6
J 2
(-4500 5250);
DISPLAY 0.489362 (-4500 5250);
PAINT SKYBLUE (-4500 5250);
FORCEPROP 1 LAST WATTAGE 1/16W
J 0
(-4275 5175);
DISPLAY 0.489362 (-4275 5175);
PAINT SKYBLUE (-4275 5175);
FORCEPROP 1 LAST PACK_TYPE 0402LF
J 0
(-4275 5125);
DISPLAY 0.489362 (-4275 5125);
PAINT SKYBLUE (-4275 5125);
FORCEPROP 2 LAST CDS_LIB pure_quanta
J 0
(-4375 5225);
DISPLAY INVISIBLE (-4375 5225);
FORCEPROP 1 LAST PATH I47
J 0
(-4425 5375);
DISPLAY 0.978723 (-4425 5375);
PAINT WHITE (-4425 5375);
DISPLAY INVISIBLE (-4425 5375);
FORCEPROP 1 LAST PART_NUMBER CS-5602FB01
J 0
(-4625 5175);
DISPLAY 0.489362 (-4625 5175);
PAINT SKYBLUE (-4625 5175);
DISPLAY INVISIBLE (-4625 5175);
FORCEADD Q_CAP..1
(-4775 5775);
FORCEPROP 1 LAST LOCATION PC292_3
J 0
(-4725 5875);
DISPLAY 0.489362 (-4725 5875);
PAINT SKYBLUE (-4725 5875);
FORCEPROP 0 LAST $SEC 1
J 0
(-4725 5900);
DISPLAY 0.680851 (-4725 5900);
PAINT MONO (-4725 5900);
DISPLAY INVISIBLE (-4725 5900);
FORCEPROP 0 LAST CDS_SEC 1
J 0
(-4725 5900);
DISPLAY 1.021277 (-4725 5900);
DISPLAY INVISIBLE (-4725 5900);
FORCEPROP 1 LASTPIN (-4775 5875) $PN 1
J 0
(-4765 5855);
DISPLAY 0.489362 (-4765 5855);
PAINT MONO (-4765 5855);
FORCEPROP 1 LASTPIN (-4775 5675) $PN 2
J 0
(-4765 5655);
DISPLAY 0.489362 (-4765 5655);
PAINT MONO (-4765 5655);
FORCEPROP 1 LAST VOLTAGE 25V
J 0
(-4725 5775);
DISPLAY 0.489362 (-4725 5775);
PAINT SKYBLUE (-4725 5775);
FORCEPROP 1 LAST VALUE 1UF
J 0
(-4725 5825);
DISPLAY 0.489362 (-4725 5825);
PAINT SKYBLUE (-4725 5825);
FORCEPROP 1 LAST TOLERANCE 10%
J 0
(-4725 5725);
DISPLAY 0.489362 (-4725 5725);
PAINT SKYBLUE (-4725 5725);
FORCEPROP 1 LAST MATERIAL X6S
J 0
(-4725 5675);
DISPLAY 0.489362 (-4725 5675);
PAINT SKYBLUE (-4725 5675);
FORCEPROP 1 LAST PACK_TYPE C0402
J 0
(-4725 5575);
DISPLAY 0.489362 (-4725 5575);
PAINT SKYBLUE (-4725 5575);
FORCEPROP 2 LAST CDS_LIB pure_quanta
J 0
(-4775 5775);
DISPLAY INVISIBLE (-4775 5775);
FORCEPROP 1 LAST PATH I48
J 0
(-4725 5925);
DISPLAY 0.978723 (-4725 5925);
PAINT WHITE (-4725 5925);
DISPLAY INVISIBLE (-4725 5925);
FORCEPROP 1 LAST PART_NUMBER CH5104KEB02
J 0
(-4725 5625);
DISPLAY 0.489362 (-4725 5625);
PAINT SKYBLUE (-4725 5625);
DISPLAY INVISIBLE (-4725 5625);
FORCEADD Q_CAP..1
(-4450 5775);
FORCEPROP 1 LAST LOCATION PC294_3
J 0
(-4400 5875);
DISPLAY 0.489362 (-4400 5875);
PAINT SKYBLUE (-4400 5875);
FORCEPROP 0 LAST $SEC 1
J 0
(-4400 5900);
DISPLAY 0.680851 (-4400 5900);
PAINT MONO (-4400 5900);
DISPLAY INVISIBLE (-4400 5900);
FORCEPROP 0 LAST CDS_SEC 1
J 0
(-4400 5900);
DISPLAY 1.021277 (-4400 5900);
DISPLAY INVISIBLE (-4400 5900);
FORCEPROP 1 LASTPIN (-4450 5875) $PN 1
J 0
(-4440 5855);
DISPLAY 0.489362 (-4440 5855);
PAINT MONO (-4440 5855);
FORCEPROP 1 LASTPIN (-4450 5675) $PN 2
J 0
(-4440 5655);
DISPLAY 0.489362 (-4440 5655);
PAINT MONO (-4440 5655);
FORCEPROP 1 LAST PACK_TYPE C0805
J 0
(-4400 5575);
DISPLAY 0.489362 (-4400 5575);
PAINT SKYBLUE (-4400 5575);
FORCEPROP 1 LAST TOLERANCE 20%
J 0
(-4400 5725);
DISPLAY 0.489362 (-4400 5725);
PAINT SKYBLUE (-4400 5725);
FORCEPROP 1 LAST VOLTAGE 16V
J 0
(-4400 5775);
DISPLAY 0.489362 (-4400 5775);
PAINT SKYBLUE (-4400 5775);
FORCEPROP 1 LAST VALUE 22UF
J 0
(-4400 5825);
DISPLAY 0.489362 (-4400 5825);
PAINT SKYBLUE (-4400 5825);
FORCEPROP 1 LAST MATERIAL X6S
J 0
(-4400 5675);
DISPLAY 0.489362 (-4400 5675);
PAINT SKYBLUE (-4400 5675);
FORCEPROP 2 LAST CDS_LIB pure_quanta
J 0
(-4450 5775);
DISPLAY INVISIBLE (-4450 5775);
FORCEPROP 1 LAST PATH I49
J 0
(-4400 5925);
DISPLAY 0.978723 (-4400 5925);
PAINT WHITE (-4400 5925);
DISPLAY INVISIBLE (-4400 5925);
FORCEPROP 1 LAST PART_NUMBER CH6223MEA01
J 0
(-4400 5625);
DISPLAY 0.489362 (-4400 5625);
PAINT SKYBLUE (-4400 5625);
DISPLAY INVISIBLE (-4400 5625);
FORCEADD UNIVERSAL_GND..1
(-7150 1725);
FORCEPROP 3 LASTPIN (-7150 1775) SIG_NAME GND\g
J 0
(-7140 1785);
DISPLAY 0.659574 (-7140 1785);
PAINT MONO (-7140 1785);
DISPLAY INVISIBLE (-7140 1785);
FORCEPROP 2 LAST CDS_LIB pure_quanta_power
J 0
(-7150 1725);
DISPLAY INVISIBLE (-7150 1725);
FORCEPROP 1 LAST HDL_POWER GND
J 1
(-7125 1650);
DISPLAY 0.872340 (-7125 1650);
PAINT GREEN (-7125 1650);
DISPLAY INVISIBLE (-7125 1650);
FORCEPROP 1 LAST PATH I5
J 0
(-7075 1725);
DISPLAY 0.872340 (-7075 1725);
PAINT AQUA (-7075 1725);
DISPLAY INVISIBLE (-7075 1725);
FORCEADD Q_CAP..1
(-4125 5775);
FORCEPROP 1 LAST LOCATION PC296_3
J 0
(-4075 5875);
DISPLAY 0.489362 (-4075 5875);
PAINT SKYBLUE (-4075 5875);
FORCEPROP 0 LAST $SEC 1
J 0
(-4075 5900);
DISPLAY 0.680851 (-4075 5900);
PAINT MONO (-4075 5900);
DISPLAY INVISIBLE (-4075 5900);
FORCEPROP 0 LAST CDS_SEC 1
J 0
(-4075 5900);
DISPLAY 1.021277 (-4075 5900);
DISPLAY INVISIBLE (-4075 5900);
FORCEPROP 1 LASTPIN (-4125 5875) $PN 1
J 0
(-4115 5855);
DISPLAY 0.489362 (-4115 5855);
PAINT MONO (-4115 5855);
FORCEPROP 1 LASTPIN (-4125 5675) $PN 2
J 0
(-4115 5655);
DISPLAY 0.489362 (-4115 5655);
PAINT MONO (-4115 5655);
FORCEPROP 1 LAST VALUE 22UF
J 0
(-4075 5825);
DISPLAY 0.489362 (-4075 5825);
PAINT SKYBLUE (-4075 5825);
FORCEPROP 1 LAST TOLERANCE 20%
J 0
(-4075 5725);
DISPLAY 0.489362 (-4075 5725);
PAINT SKYBLUE (-4075 5725);
FORCEPROP 1 LAST VOLTAGE 16V
J 0
(-4075 5775);
DISPLAY 0.489362 (-4075 5775);
PAINT SKYBLUE (-4075 5775);
FORCEPROP 1 LAST MATERIAL X6S
J 0
(-4075 5675);
DISPLAY 0.489362 (-4075 5675);
PAINT SKYBLUE (-4075 5675);
FORCEPROP 1 LAST PACK_TYPE C0805
J 0
(-4075 5575);
DISPLAY 0.489362 (-4075 5575);
PAINT SKYBLUE (-4075 5575);
FORCEPROP 2 LAST CDS_LIB pure_quanta
J 0
(-4125 5775);
DISPLAY INVISIBLE (-4125 5775);
FORCEPROP 1 LAST PATH I50
J 0
(-4075 5925);
DISPLAY 0.978723 (-4075 5925);
PAINT WHITE (-4075 5925);
DISPLAY INVISIBLE (-4075 5925);
FORCEPROP 1 LAST PART_NUMBER CH6223MEA01
J 0
(-4075 5625);
DISPLAY 0.489362 (-4075 5625);
PAINT SKYBLUE (-4075 5625);
DISPLAY INVISIBLE (-4075 5625);
FORCEADD OFFPAGE..3
R 2
(-3250 1325);
FORCEPROP 2 LAST $XR0 212 
J 0
(-3530 1325);
DISPLAY 0.638298 (-3530 1325);
PAINT MONO (-3530 1325);
FORCEPROP 2 LAST CDS_LIB standard
J 2
(-3250 1325);
DISPLAY INVISIBLE (-3250 1325);
FORCEPROP 1 LAST OFFPAGE TRUE
J 2
(-3575 1200);
DISPLAY 0.872340 (-3575 1200);
PAINT GREEN (-3575 1200);
DISPLAY INVISIBLE (-3575 1200);
FORCEPROP 1 LAST COMMENT_BODY TRUE
J 2
(-3200 1225);
DISPLAY 0.872340 (-3200 1225);
PAINT GREEN (-3200 1225);
DISPLAY INVISIBLE (-3200 1225);
FORCEPROP 2 LAST PATH I51
J 0
(-3550 1375);
DISPLAY 0.680851 (-3550 1375);
DISPLAY INVISIBLE (-3550 1375);
FORCEADD Q_CAP..1
(-3325 1800);
FORCEPROP 1 LAST LOCATION PC301
J 0
(-3275 1925);
DISPLAY 0.489362 (-3275 1925);
PAINT SKYBLUE (-3275 1925);
FORCEPROP 0 LAST $SEC 1
J 0
(-3275 1950);
DISPLAY 0.680851 (-3275 1950);
PAINT MONO (-3275 1950);
DISPLAY INVISIBLE (-3275 1950);
FORCEPROP 0 LAST CDS_SEC 1
J 0
(-3275 1950);
DISPLAY 1.021277 (-3275 1950);
DISPLAY INVISIBLE (-3275 1950);
FORCEPROP 1 LASTPIN (-3325 1900) $PN 1
J 0
(-3315 1880);
DISPLAY 0.489362 (-3315 1880);
PAINT MONO (-3315 1880);
FORCEPROP 1 LASTPIN (-3325 1700) $PN 2
J 0
(-3315 1680);
DISPLAY 0.489362 (-3315 1680);
PAINT MONO (-3315 1680);
FORCEPROP 1 LAST PACK_TYPE 0402
J 0
(-3275 1625);
DISPLAY 0.489362 (-3275 1625);
PAINT SKYBLUE (-3275 1625);
FORCEPROP 1 LAST VOLTAGE 16V
J 0
(-3275 1825);
DISPLAY 0.489362 (-3275 1825);
PAINT SKYBLUE (-3275 1825);
FORCEPROP 1 LAST VALUE 0.22UF
J 0
(-3275 1875);
DISPLAY 0.489362 (-3275 1875);
PAINT SKYBLUE (-3275 1875);
FORCEPROP 1 LAST TOLERANCE 10%
J 0
(-3275 1775);
DISPLAY 0.489362 (-3275 1775);
PAINT SKYBLUE (-3275 1775);
FORCEPROP 1 LAST MATERIAL X7R
J 0
(-3275 1725);
DISPLAY 0.489362 (-3275 1725);
PAINT SKYBLUE (-3275 1725);
FORCEPROP 2 LAST CDS_LIB pure_quanta
J 0
(-3325 1800);
DISPLAY INVISIBLE (-3325 1800);
FORCEPROP 1 LAST PATH I52
J 0
(-3275 1950);
DISPLAY 0.978723 (-3275 1950);
PAINT WHITE (-3275 1950);
DISPLAY INVISIBLE (-3275 1950);
FORCEPROP 1 LAST PART_NUMBER CH4223K1B00
J 0
(-3275 1675);
DISPLAY 0.489362 (-3275 1675);
PAINT SKYBLUE (-3275 1675);
DISPLAY INVISIBLE (-3275 1675);
FORCEADD Q_INDUCTOR4P_14..1
(-2350 1450);
FORCEPROP 1 LAST LOCATION PL32
J 0
(-2575 1705);
DISPLAY 0.489362 (-2575 1705);
PAINT SKYBLUE (-2575 1705);
FORCEPROP 0 LAST $SEC 1
J 0
(-2575 1850);
DISPLAY 0.680851 (-2575 1850);
PAINT MONO (-2575 1850);
DISPLAY INVISIBLE (-2575 1850);
FORCEPROP 0 LAST CDS_SEC 1
J 0
(-2575 1850);
DISPLAY 1.021277 (-2575 1850);
DISPLAY INVISIBLE (-2575 1850);
FORCEPROP 0 LASTPIN (-2750 1575) $PN 1
J 2
(-2760 1585);
DISPLAY 0.489362 (-2760 1585);
PAINT MONO (-2760 1585);
FORCEPROP 0 LASTPIN (-2750 1325) $PN 2
J 2
(-2760 1335);
DISPLAY 0.489362 (-2760 1335);
PAINT MONO (-2760 1335);
FORCEPROP 0 LASTPIN (-1950 1325) $PN 3
J 0
(-1940 1335);
DISPLAY 0.489362 (-1940 1335);
PAINT MONO (-1940 1335);
FORCEPROP 0 LASTPIN (-1950 1575) $PN 4
J 0
(-1940 1585);
DISPLAY 0.489362 (-1940 1585);
PAINT MONO (-1940 1585);
FORCEPROP 2 LAST VALUE 150NH
J 0
(-2575 1750);
DISPLAY 0.489362 (-2575 1750);
PAINT SKYBLUE (-2575 1750);
FORCEPROP 1 LAST MATERIAL IND
J 0
(-2575 1660);
DISPLAY 0.489362 (-2575 1660);
PAINT SKYBLUE (-2575 1660);
FORCEPROP 2 LAST PART_TYPE SMLF
J 0
(-2575 1800);
DISPLAY 1.021277 (-2575 1800);
FORCEPROP 2 LAST CDS_LIB pure_quanta
J 0
(-2350 1450);
DISPLAY INVISIBLE (-2350 1450);
FORCEPROP 1 LAST NEEDS_NO_SIZE TRUE
J 0
(-2350 1450);
DISPLAY 0.468085 (-2350 1450);
PAINT GREEN (-2350 1450);
DISPLAY INVISIBLE (-2350 1450);
FORCEPROP 1 LAST PATH I53
J 0
(-2150 1605);
DISPLAY 0.723404 (-2150 1605);
PAINT GREEN (-2150 1605);
DISPLAY INVISIBLE (-2150 1605);
FORCEPROP 1 LAST PART_NUMBER CV+15^0TZ04
J 0
(-2575 1610);
DISPLAY 0.489362 (-2575 1610);
PAINT SKYBLUE (-2575 1610);
DISPLAY INVISIBLE (-2575 1610);
FORCEADD UNIVERSAL_GND..1
(-3675 2125);
FORCEPROP 3 LASTPIN (-3675 2175) SIG_NAME GND\g
J 0
(-3665 2185);
DISPLAY 0.659574 (-3665 2185);
PAINT MONO (-3665 2185);
DISPLAY INVISIBLE (-3665 2185);
FORCEPROP 2 LAST CDS_LIB pure_quanta_power
J 0
(-3675 2125);
DISPLAY INVISIBLE (-3675 2125);
FORCEPROP 1 LAST HDL_POWER GND
J 1
(-3650 2050);
DISPLAY 0.872340 (-3650 2050);
PAINT GREEN (-3650 2050);
DISPLAY INVISIBLE (-3650 2050);
FORCEPROP 1 LAST PATH I54
J 0
(-3600 2125);
DISPLAY 0.872340 (-3600 2125);
PAINT AQUA (-3600 2125);
DISPLAY INVISIBLE (-3600 2125);
FORCEADD Q_CAP..1
(-3675 2475);
FORCEPROP 1 LAST LOCATION PC299_4
J 0
(-3625 2575);
DISPLAY 0.489362 (-3625 2575);
PAINT SKYBLUE (-3625 2575);
FORCEPROP 0 LAST $SEC 1
J 0
(-3625 2600);
DISPLAY 0.680851 (-3625 2600);
PAINT MONO (-3625 2600);
DISPLAY INVISIBLE (-3625 2600);
FORCEPROP 0 LAST CDS_SEC 1
J 0
(-3625 2600);
DISPLAY 1.021277 (-3625 2600);
DISPLAY INVISIBLE (-3625 2600);
FORCEPROP 1 LASTPIN (-3675 2575) $PN 1
J 0
(-3665 2555);
DISPLAY 0.489362 (-3665 2555);
PAINT MONO (-3665 2555);
FORCEPROP 1 LASTPIN (-3675 2375) $PN 2
J 0
(-3665 2355);
DISPLAY 0.489362 (-3665 2355);
PAINT MONO (-3665 2355);
FORCEPROP 1 LAST TOLERANCE 20%
J 0
(-3625 2425);
DISPLAY 0.489362 (-3625 2425);
PAINT SKYBLUE (-3625 2425);
FORCEPROP 1 LAST VOLTAGE 16V
J 0
(-3625 2475);
DISPLAY 0.489362 (-3625 2475);
PAINT SKYBLUE (-3625 2475);
FORCEPROP 1 LAST VALUE 22UF
J 0
(-3625 2525);
DISPLAY 0.489362 (-3625 2525);
PAINT SKYBLUE (-3625 2525);
FORCEPROP 1 LAST MATERIAL X6S
J 0
(-3625 2375);
DISPLAY 0.489362 (-3625 2375);
PAINT SKYBLUE (-3625 2375);
FORCEPROP 1 LAST PACK_TYPE C0805
J 0
(-3625 2275);
DISPLAY 0.489362 (-3625 2275);
PAINT SKYBLUE (-3625 2275);
FORCEPROP 2 LAST CDS_LIB pure_quanta
J 0
(-3675 2475);
DISPLAY INVISIBLE (-3675 2475);
FORCEPROP 1 LAST PATH I55
J 0
(-3625 2625);
DISPLAY 0.978723 (-3625 2625);
PAINT WHITE (-3625 2625);
DISPLAY INVISIBLE (-3625 2625);
FORCEPROP 1 LAST PART_NUMBER CH6223MEA01
J 0
(-3625 2325);
DISPLAY 0.489362 (-3625 2325);
PAINT SKYBLUE (-3625 2325);
DISPLAY INVISIBLE (-3625 2325);
FORCEADD VCC_CORE..1
(-3675 2775);
FORCEPROP 3 LASTPIN (-3675 2725) SIG_NAME SW_P12V_AUX_PVDDCR_CPU0_P1_FLT\g
J 0
(-3665 2735);
DISPLAY 0.659574 (-3665 2735);
PAINT MONO (-3665 2735);
DISPLAY INVISIBLE (-3665 2735);
FORCEPROP 1 LAST HDL_POWER SW_P12V_AUX_PVDDCR_CPU0_P1_FLT
J 1
(-3675 2825);
DISPLAY 0.489362 (-3675 2825);
PAINT GREEN (-3675 2825);
FORCEPROP 2 LAST CDS_LIB pure_quanta_power
J 0
(-3675 2775);
DISPLAY INVISIBLE (-3675 2775);
FORCEPROP 1 LAST PATH I56
J 0
(-3625 2800);
DISPLAY 0.872340 (-3625 2800);
PAINT AQUA (-3625 2800);
DISPLAY INVISIBLE (-3625 2800);
FORCEADD UNIVERSAL_GND..1
(-1525 1200);
FORCEPROP 3 LASTPIN (-1525 1250) SIG_NAME GND\g
J 0
(-1515 1260);
DISPLAY 0.659574 (-1515 1260);
PAINT MONO (-1515 1260);
DISPLAY INVISIBLE (-1515 1260);
FORCEPROP 2 LAST CDS_LIB pure_quanta_power
J 0
(-1525 1200);
DISPLAY INVISIBLE (-1525 1200);
FORCEPROP 1 LAST HDL_POWER GND
J 1
(-1500 1125);
DISPLAY 0.872340 (-1500 1125);
PAINT GREEN (-1500 1125);
DISPLAY INVISIBLE (-1500 1125);
FORCEPROP 1 LAST PATH I57
J 0
(-1450 1200);
DISPLAY 0.872340 (-1450 1200);
PAINT AQUA (-1450 1200);
DISPLAY INVISIBLE (-1450 1200);
FORCEADD Q_CAP..1
(-1000 1400);
FORCEPROP 1 LAST LOCATION PC303_4
J 0
(-950 1500);
DISPLAY 0.489362 (-950 1500);
PAINT SKYBLUE (-950 1500);
FORCEPROP 0 LAST $SEC 1
J 0
(-950 1525);
DISPLAY 0.680851 (-950 1525);
PAINT MONO (-950 1525);
DISPLAY INVISIBLE (-950 1525);
FORCEPROP 0 LAST CDS_SEC 1
J 0
(-950 1525);
DISPLAY 1.021277 (-950 1525);
DISPLAY INVISIBLE (-950 1525);
FORCEPROP 1 LASTPIN (-1000 1500) $PN 1
J 0
(-990 1480);
DISPLAY 0.489362 (-990 1480);
PAINT MONO (-990 1480);
FORCEPROP 1 LASTPIN (-1000 1300) $PN 2
J 0
(-990 1280);
DISPLAY 0.489362 (-990 1280);
PAINT MONO (-990 1280);
FORCEPROP 1 LAST PACK_TYPE C0805
J 0
(-950 1200);
DISPLAY 0.489362 (-950 1200);
PAINT SKYBLUE (-950 1200);
FORCEPROP 1 LAST MATERIAL X6S
J 0
(-950 1300);
DISPLAY 0.489362 (-950 1300);
PAINT SKYBLUE (-950 1300);
FORCEPROP 1 LAST TOLERANCE 20%
J 0
(-950 1350);
DISPLAY 0.489362 (-950 1350);
PAINT SKYBLUE (-950 1350);
FORCEPROP 1 LAST VALUE 22UF
J 0
(-950 1450);
DISPLAY 0.489362 (-950 1450);
PAINT SKYBLUE (-950 1450);
FORCEPROP 1 LAST VOLTAGE 4V
J 0
(-950 1400);
DISPLAY 0.489362 (-950 1400);
PAINT SKYBLUE (-950 1400);
FORCEPROP 2 LAST CDS_LIB pure_quanta
J 0
(-1000 1400);
DISPLAY INVISIBLE (-1000 1400);
FORCEPROP 1 LAST PATH I58
J 0
(-950 1550);
DISPLAY 0.978723 (-950 1550);
PAINT WHITE (-950 1550);
DISPLAY INVISIBLE (-950 1550);
FORCEPROP 1 LAST PART_NUMBER CH622KMEA03
J 0
(-950 1250);
DISPLAY 0.489362 (-950 1250);
PAINT SKYBLUE (-950 1250);
DISPLAY INVISIBLE (-950 1250);
FORCEADD UNIVERSAL_GND..1
(-575 1050);
FORCEPROP 3 LASTPIN (-575 1100) SIG_NAME GND\g
J 0
(-565 1110);
DISPLAY 0.659574 (-565 1110);
PAINT MONO (-565 1110);
DISPLAY INVISIBLE (-565 1110);
FORCEPROP 2 LAST CDS_LIB pure_quanta_power
J 0
(-575 1050);
DISPLAY INVISIBLE (-575 1050);
FORCEPROP 1 LAST HDL_POWER GND
J 1
(-550 975);
DISPLAY 0.872340 (-550 975);
PAINT GREEN (-550 975);
DISPLAY INVISIBLE (-550 975);
FORCEPROP 1 LAST PATH I59
J 0
(-500 1050);
DISPLAY 0.872340 (-500 1050);
PAINT AQUA (-500 1050);
DISPLAY INVISIBLE (-500 1050);
FORCEADD Q_CAP..1
(-7150 1925);
FORCEPROP 1 LAST LOCATION PC287
J 0
(-7100 2025);
DISPLAY 0.489362 (-7100 2025);
PAINT SKYBLUE (-7100 2025);
FORCEPROP 0 LAST $SEC 1
J 0
(-7100 2075);
DISPLAY 0.680851 (-7100 2075);
PAINT MONO (-7100 2075);
DISPLAY INVISIBLE (-7100 2075);
FORCEPROP 0 LAST CDS_SEC 1
J 0
(-7100 2075);
DISPLAY 1.021277 (-7100 2075);
DISPLAY INVISIBLE (-7100 2075);
FORCEPROP 1 LASTPIN (-7150 2025) $PN 1
J 0
(-7140 2005);
DISPLAY 0.489362 (-7140 2005);
PAINT MONO (-7140 2005);
FORCEPROP 1 LASTPIN (-7150 1825) $PN 2
J 0
(-7140 1805);
DISPLAY 0.489362 (-7140 1805);
PAINT MONO (-7140 1805);
FORCEPROP 1 LAST PACK_TYPE C0402
J 0
(-7100 1725);
DISPLAY 0.489362 (-7100 1725);
PAINT SKYBLUE (-7100 1725);
FORCEPROP 1 LAST VOLTAGE 10V
J 0
(-7100 1925);
DISPLAY 0.489362 (-7100 1925);
PAINT SKYBLUE (-7100 1925);
FORCEPROP 1 LAST VALUE 2.2UF
J 0
(-7100 1975);
DISPLAY 0.489362 (-7100 1975);
PAINT SKYBLUE (-7100 1975);
FORCEPROP 1 LAST TOLERANCE 10%
J 0
(-7100 1875);
DISPLAY 0.489362 (-7100 1875);
PAINT SKYBLUE (-7100 1875);
FORCEPROP 1 LAST MATERIAL X6S
J 0
(-7100 1825);
DISPLAY 0.489362 (-7100 1825);
PAINT SKYBLUE (-7100 1825);
FORCEPROP 2 LAST CDS_LIB pure_quanta
J 0
(-7150 1925);
DISPLAY INVISIBLE (-7150 1925);
FORCEPROP 1 LAST PATH I6
J 0
(-7100 2075);
DISPLAY 0.978723 (-7100 2075);
PAINT WHITE (-7100 2075);
DISPLAY INVISIBLE (-7100 2075);
FORCEPROP 1 LAST PART_NUMBER CH5222KEB01
J 0
(-7100 1775);
DISPLAY 0.489362 (-7100 1775);
PAINT SKYBLUE (-7100 1775);
DISPLAY INVISIBLE (-7100 1775);
FORCEADD Q_CAP..1
(-575 1400);
FORCEPROP 1 LAST LOCATION PC305_4
J 0
(-525 1500);
DISPLAY 0.489362 (-525 1500);
PAINT SKYBLUE (-525 1500);
FORCEPROP 0 LAST $SEC 1
J 0
(-525 1525);
DISPLAY 0.680851 (-525 1525);
PAINT MONO (-525 1525);
DISPLAY INVISIBLE (-525 1525);
FORCEPROP 0 LAST CDS_SEC 1
J 0
(-525 1525);
DISPLAY 1.021277 (-525 1525);
DISPLAY INVISIBLE (-525 1525);
FORCEPROP 1 LASTPIN (-575 1500) $PN 1
J 0
(-565 1480);
DISPLAY 0.489362 (-565 1480);
PAINT MONO (-565 1480);
FORCEPROP 1 LASTPIN (-575 1300) $PN 2
J 0
(-565 1280);
DISPLAY 0.489362 (-565 1280);
PAINT MONO (-565 1280);
FORCEPROP 1 LAST PACK_TYPE C0805
J 0
(-525 1200);
DISPLAY 0.489362 (-525 1200);
PAINT SKYBLUE (-525 1200);
FORCEPROP 1 LAST MATERIAL X6S
J 0
(-525 1300);
DISPLAY 0.489362 (-525 1300);
PAINT SKYBLUE (-525 1300);
FORCEPROP 1 LAST TOLERANCE 20%
J 0
(-525 1350);
DISPLAY 0.489362 (-525 1350);
PAINT SKYBLUE (-525 1350);
FORCEPROP 1 LAST VALUE 22UF
J 0
(-525 1450);
DISPLAY 0.489362 (-525 1450);
PAINT SKYBLUE (-525 1450);
FORCEPROP 1 LAST VOLTAGE 4V
J 0
(-525 1400);
DISPLAY 0.489362 (-525 1400);
PAINT SKYBLUE (-525 1400);
FORCEPROP 2 LAST CDS_LIB pure_quanta
J 0
(-575 1400);
DISPLAY INVISIBLE (-575 1400);
FORCEPROP 1 LAST PATH I60
J 0
(-525 1550);
DISPLAY 0.978723 (-525 1550);
PAINT WHITE (-525 1550);
DISPLAY INVISIBLE (-525 1550);
FORCEPROP 1 LAST PART_NUMBER CH622KMEA03
J 0
(-525 1250);
DISPLAY 0.489362 (-525 1250);
PAINT SKYBLUE (-525 1250);
DISPLAY INVISIBLE (-525 1250);
FORCEADD VCC_CORE..1
(-575 1725);
FORCEPROP 3 LASTPIN (-575 1675) SIG_NAME PVDDCR_CPU0_P1\g
J 0
(-565 1685);
DISPLAY 0.659574 (-565 1685);
PAINT MONO (-565 1685);
DISPLAY INVISIBLE (-565 1685);
FORCEPROP 1 LAST HDL_POWER PVDDCR_CPU0_P1
J 1
(-575 1775);
DISPLAY 0.489362 (-575 1775);
PAINT GREEN (-575 1775);
FORCEPROP 2 LAST CDS_LIB pure_quanta_power
J 0
(-575 1725);
DISPLAY INVISIBLE (-575 1725);
FORCEPROP 1 LAST PATH I61
J 0
(-525 1750);
DISPLAY 0.872340 (-525 1750);
PAINT AQUA (-525 1750);
DISPLAY INVISIBLE (-525 1750);
FORCEADD OFFPAGE..3
R 2
(-3400 4625);
FORCEPROP 2 LAST $XR0 211 
J 0
(-3680 4625);
DISPLAY 0.638298 (-3680 4625);
PAINT MONO (-3680 4625);
FORCEPROP 2 LAST CDS_LIB standard
J 2
(-3400 4625);
DISPLAY INVISIBLE (-3400 4625);
FORCEPROP 1 LAST OFFPAGE TRUE
J 2
(-3725 4500);
DISPLAY 0.872340 (-3725 4500);
PAINT GREEN (-3725 4500);
DISPLAY INVISIBLE (-3725 4500);
FORCEPROP 1 LAST COMMENT_BODY TRUE
J 2
(-3350 4525);
DISPLAY 0.872340 (-3350 4525);
PAINT GREEN (-3350 4525);
DISPLAY INVISIBLE (-3350 4525);
FORCEPROP 2 LAST PATH I62
J 0
(-3675 4675);
DISPLAY 0.680851 (-3675 4675);
DISPLAY INVISIBLE (-3675 4675);
FORCEADD Q_CAP..1
(-3400 5100);
FORCEPROP 1 LAST LOCATION PC300
J 0
(-3350 5225);
DISPLAY 0.489362 (-3350 5225);
PAINT SKYBLUE (-3350 5225);
FORCEPROP 0 LAST $SEC 1
J 0
(-3350 5250);
DISPLAY 0.680851 (-3350 5250);
PAINT MONO (-3350 5250);
DISPLAY INVISIBLE (-3350 5250);
FORCEPROP 0 LAST CDS_SEC 1
J 0
(-3350 5250);
DISPLAY 1.021277 (-3350 5250);
DISPLAY INVISIBLE (-3350 5250);
FORCEPROP 1 LASTPIN (-3400 5200) $PN 1
J 0
(-3390 5180);
DISPLAY 0.489362 (-3390 5180);
PAINT MONO (-3390 5180);
FORCEPROP 1 LASTPIN (-3400 5000) $PN 2
J 0
(-3390 4980);
DISPLAY 0.489362 (-3390 4980);
PAINT MONO (-3390 4980);
FORCEPROP 1 LAST PACK_TYPE 0402
J 0
(-3350 4925);
DISPLAY 0.489362 (-3350 4925);
PAINT SKYBLUE (-3350 4925);
FORCEPROP 1 LAST MATERIAL X7R
J 0
(-3350 5025);
DISPLAY 0.489362 (-3350 5025);
PAINT SKYBLUE (-3350 5025);
FORCEPROP 1 LAST TOLERANCE 10%
J 0
(-3350 5075);
DISPLAY 0.489362 (-3350 5075);
PAINT SKYBLUE (-3350 5075);
FORCEPROP 1 LAST VOLTAGE 16V
J 0
(-3350 5125);
DISPLAY 0.489362 (-3350 5125);
PAINT SKYBLUE (-3350 5125);
FORCEPROP 1 LAST VALUE 0.22UF
J 0
(-3350 5175);
DISPLAY 0.489362 (-3350 5175);
PAINT SKYBLUE (-3350 5175);
FORCEPROP 2 LAST CDS_LIB pure_quanta
J 0
(-3400 5100);
DISPLAY INVISIBLE (-3400 5100);
FORCEPROP 1 LAST PATH I63
J 0
(-3350 5250);
DISPLAY 0.978723 (-3350 5250);
PAINT WHITE (-3350 5250);
DISPLAY INVISIBLE (-3350 5250);
FORCEPROP 1 LAST PART_NUMBER CH4223K1B00
J 0
(-3350 4975);
DISPLAY 0.489362 (-3350 4975);
PAINT SKYBLUE (-3350 4975);
DISPLAY INVISIBLE (-3350 4975);
FORCEADD UNIVERSAL_GND..1
(-3825 5450);
FORCEPROP 3 LASTPIN (-3825 5500) SIG_NAME GND\g
J 0
(-3815 5510);
DISPLAY 0.659574 (-3815 5510);
PAINT MONO (-3815 5510);
DISPLAY INVISIBLE (-3815 5510);
FORCEPROP 2 LAST CDS_LIB pure_quanta_power
J 0
(-3825 5450);
DISPLAY INVISIBLE (-3825 5450);
FORCEPROP 1 LAST HDL_POWER GND
J 1
(-3800 5375);
DISPLAY 0.872340 (-3800 5375);
PAINT GREEN (-3800 5375);
DISPLAY INVISIBLE (-3800 5375);
FORCEPROP 1 LAST PATH I64
J 0
(-3750 5450);
DISPLAY 0.872340 (-3750 5450);
PAINT AQUA (-3750 5450);
DISPLAY INVISIBLE (-3750 5450);
FORCEADD Q_CAP..1
(-3825 5775);
FORCEPROP 1 LAST LOCATION PC298_3
J 0
(-3775 5875);
DISPLAY 0.489362 (-3775 5875);
PAINT SKYBLUE (-3775 5875);
FORCEPROP 0 LAST $SEC 1
J 0
(-3775 5900);
DISPLAY 0.680851 (-3775 5900);
PAINT MONO (-3775 5900);
DISPLAY INVISIBLE (-3775 5900);
FORCEPROP 0 LAST CDS_SEC 1
J 0
(-3775 5900);
DISPLAY 1.021277 (-3775 5900);
DISPLAY INVISIBLE (-3775 5900);
FORCEPROP 1 LASTPIN (-3825 5875) $PN 1
J 0
(-3815 5855);
DISPLAY 0.489362 (-3815 5855);
PAINT MONO (-3815 5855);
FORCEPROP 1 LASTPIN (-3825 5675) $PN 2
J 0
(-3815 5655);
DISPLAY 0.489362 (-3815 5655);
PAINT MONO (-3815 5655);
FORCEPROP 1 LAST TOLERANCE 20%
J 0
(-3775 5725);
DISPLAY 0.489362 (-3775 5725);
PAINT SKYBLUE (-3775 5725);
FORCEPROP 1 LAST VOLTAGE 16V
J 0
(-3775 5775);
DISPLAY 0.489362 (-3775 5775);
PAINT SKYBLUE (-3775 5775);
FORCEPROP 1 LAST VALUE 22UF
J 0
(-3775 5825);
DISPLAY 0.489362 (-3775 5825);
PAINT SKYBLUE (-3775 5825);
FORCEPROP 1 LAST MATERIAL X6S
J 0
(-3775 5675);
DISPLAY 0.489362 (-3775 5675);
PAINT SKYBLUE (-3775 5675);
FORCEPROP 1 LAST PACK_TYPE C0805
J 0
(-3775 5575);
DISPLAY 0.489362 (-3775 5575);
PAINT SKYBLUE (-3775 5575);
FORCEPROP 2 LAST CDS_LIB pure_quanta
J 0
(-3825 5775);
DISPLAY INVISIBLE (-3825 5775);
FORCEPROP 1 LAST PATH I65
J 0
(-3775 5925);
DISPLAY 0.978723 (-3775 5925);
PAINT WHITE (-3775 5925);
DISPLAY INVISIBLE (-3775 5925);
FORCEPROP 1 LAST PART_NUMBER CH6223MEA01
J 0
(-3775 5625);
DISPLAY 0.489362 (-3775 5625);
PAINT SKYBLUE (-3775 5625);
DISPLAY INVISIBLE (-3775 5625);
FORCEADD VCC_CORE..1
(-3825 6075);
FORCEPROP 3 LASTPIN (-3825 6025) SIG_NAME SW_P12V_AUX_PVDDCR_CPU0_P1_FLT\g
J 0
(-3815 6035);
DISPLAY 0.659574 (-3815 6035);
PAINT MONO (-3815 6035);
DISPLAY INVISIBLE (-3815 6035);
FORCEPROP 1 LAST HDL_POWER SW_P12V_AUX_PVDDCR_CPU0_P1_FLT
J 1
(-3825 6125);
DISPLAY 0.489362 (-3825 6125);
PAINT GREEN (-3825 6125);
FORCEPROP 2 LAST CDS_LIB pure_quanta_power
J 0
(-3825 6075);
DISPLAY INVISIBLE (-3825 6075);
FORCEPROP 1 LAST PATH I66
J 0
(-3775 6100);
DISPLAY 0.872340 (-3775 6100);
PAINT AQUA (-3775 6100);
DISPLAY INVISIBLE (-3775 6100);
FORCEADD Q_INDUCTOR4P_14..1
(-2450 4750);
FORCEPROP 1 LAST LOCATION PL31
J 0
(-2675 5005);
DISPLAY 0.489362 (-2675 5005);
PAINT SKYBLUE (-2675 5005);
FORCEPROP 0 LAST $SEC 1
J 0
(-2675 5150);
DISPLAY 0.680851 (-2675 5150);
PAINT MONO (-2675 5150);
DISPLAY INVISIBLE (-2675 5150);
FORCEPROP 0 LAST CDS_SEC 1
J 0
(-2675 5150);
DISPLAY 1.021277 (-2675 5150);
DISPLAY INVISIBLE (-2675 5150);
FORCEPROP 0 LASTPIN (-2850 4875) $PN 1
J 2
(-2860 4885);
DISPLAY 0.489362 (-2860 4885);
PAINT MONO (-2860 4885);
FORCEPROP 0 LASTPIN (-2850 4625) $PN 2
J 2
(-2860 4635);
DISPLAY 0.489362 (-2860 4635);
PAINT MONO (-2860 4635);
FORCEPROP 0 LASTPIN (-2050 4625) $PN 3
J 0
(-2040 4635);
DISPLAY 0.489362 (-2040 4635);
PAINT MONO (-2040 4635);
FORCEPROP 0 LASTPIN (-2050 4875) $PN 4
J 0
(-2040 4885);
DISPLAY 0.489362 (-2040 4885);
PAINT MONO (-2040 4885);
FORCEPROP 2 LAST PART_TYPE SMLF
J 0
(-2675 5100);
DISPLAY 1.021277 (-2675 5100);
FORCEPROP 2 LAST VALUE 150NH
J 0
(-2675 5050);
DISPLAY 0.489362 (-2675 5050);
PAINT SKYBLUE (-2675 5050);
FORCEPROP 1 LAST MATERIAL IND
J 0
(-2675 4960);
DISPLAY 0.489362 (-2675 4960);
PAINT SKYBLUE (-2675 4960);
FORCEPROP 1 LAST NEEDS_NO_SIZE TRUE
J 0
(-2450 4750);
DISPLAY 0.468085 (-2450 4750);
PAINT GREEN (-2450 4750);
DISPLAY INVISIBLE (-2450 4750);
FORCEPROP 2 LAST CDS_LIB pure_quanta
J 0
(-2450 4750);
DISPLAY INVISIBLE (-2450 4750);
FORCEPROP 1 LAST PATH I67
J 0
(-2250 4905);
DISPLAY 0.723404 (-2250 4905);
PAINT GREEN (-2250 4905);
DISPLAY INVISIBLE (-2250 4905);
FORCEPROP 1 LAST PART_NUMBER CV+15^0TZ04
J 0
(-2675 4910);
DISPLAY 0.489362 (-2675 4910);
PAINT SKYBLUE (-2675 4910);
DISPLAY INVISIBLE (-2675 4910);
FORCEADD OFFPAGE..3
(-1475 4625);
FORCEPROP 2 LAST $XR0 212 
J 0
(-1141 4625);
DISPLAY 0.638298 (-1141 4625);
PAINT MONO (-1141 4625);
FORCEPROP 2 LAST CDS_LIB standard
J 2
(-1475 4625);
DISPLAY INVISIBLE (-1475 4625);
FORCEPROP 1 LAST OFFPAGE TRUE
J 0
(-1150 4500);
DISPLAY 0.872340 (-1150 4500);
PAINT GREEN (-1150 4500);
DISPLAY INVISIBLE (-1150 4500);
FORCEPROP 1 LAST COMMENT_BODY TRUE
J 0
(-1525 4525);
DISPLAY 0.872340 (-1525 4525);
PAINT GREEN (-1525 4525);
DISPLAY INVISIBLE (-1525 4525);
FORCEPROP 2 LAST PATH I68
J 0
(-1150 4675);
DISPLAY 0.680851 (-1150 4675);
DISPLAY INVISIBLE (-1150 4675);
FORCEADD Q_CAP..1
(-1050 4700);
FORCEPROP 1 LAST LOCATION PC302_3
J 0
(-1000 4800);
DISPLAY 0.489362 (-1000 4800);
PAINT SKYBLUE (-1000 4800);
FORCEPROP 0 LAST $SEC 1
J 0
(-1000 4825);
DISPLAY 0.680851 (-1000 4825);
PAINT MONO (-1000 4825);
DISPLAY INVISIBLE (-1000 4825);
FORCEPROP 0 LAST CDS_SEC 1
J 0
(-1000 4825);
DISPLAY 1.021277 (-1000 4825);
DISPLAY INVISIBLE (-1000 4825);
FORCEPROP 1 LASTPIN (-1050 4800) $PN 1
J 0
(-1040 4780);
DISPLAY 0.489362 (-1040 4780);
PAINT MONO (-1040 4780);
FORCEPROP 1 LASTPIN (-1050 4600) $PN 2
J 0
(-1040 4580);
DISPLAY 0.489362 (-1040 4580);
PAINT MONO (-1040 4580);
FORCEPROP 1 LAST PACK_TYPE C0805
J 0
(-1000 4500);
DISPLAY 0.489362 (-1000 4500);
PAINT SKYBLUE (-1000 4500);
FORCEPROP 1 LAST MATERIAL X6S
J 0
(-1000 4600);
DISPLAY 0.489362 (-1000 4600);
PAINT SKYBLUE (-1000 4600);
FORCEPROP 1 LAST TOLERANCE 20%
J 0
(-1000 4650);
DISPLAY 0.489362 (-1000 4650);
PAINT SKYBLUE (-1000 4650);
FORCEPROP 1 LAST VALUE 22UF
J 0
(-1000 4750);
DISPLAY 0.489362 (-1000 4750);
PAINT SKYBLUE (-1000 4750);
FORCEPROP 1 LAST VOLTAGE 4V
J 0
(-1000 4700);
DISPLAY 0.489362 (-1000 4700);
PAINT SKYBLUE (-1000 4700);
FORCEPROP 2 LAST CDS_LIB pure_quanta
J 0
(-1050 4700);
DISPLAY INVISIBLE (-1050 4700);
FORCEPROP 1 LAST PATH I69
J 0
(-1000 4850);
DISPLAY 0.978723 (-1000 4850);
PAINT WHITE (-1000 4850);
DISPLAY INVISIBLE (-1000 4850);
FORCEPROP 1 LAST PART_NUMBER CH622KMEA03
J 0
(-1000 4550);
DISPLAY 0.489362 (-1000 4550);
PAINT SKYBLUE (-1000 4550);
DISPLAY INVISIBLE (-1000 4550);
FORCEADD OFFPAGE..2
R 2
(-6825 1575);
FORCEPROP 2 LAST $XR0 210 
J 0
(-7110 1575);
DISPLAY 0.638298 (-7110 1575);
PAINT MONO (-7110 1575);
FORCEPROP 2 LAST CDS_LIB standard
J 2
(-6825 1575);
DISPLAY INVISIBLE (-6825 1575);
FORCEPROP 1 LAST OFFPAGE TRUE
J 2
(-7150 1450);
DISPLAY 0.872340 (-7150 1450);
PAINT GREEN (-7150 1450);
DISPLAY INVISIBLE (-7150 1450);
FORCEPROP 1 LAST COMMENT_BODY TRUE
J 2
(-6780 1480);
DISPLAY 0.872340 (-6780 1480);
PAINT GREEN (-6780 1480);
DISPLAY INVISIBLE (-6780 1480);
FORCEPROP 2 LAST PATH I7
J 0
(-7075 1625);
DISPLAY 0.680851 (-7075 1625);
DISPLAY INVISIBLE (-7075 1625);
FORCEADD UNIVERSAL_GND..1
(-625 4350);
FORCEPROP 3 LASTPIN (-625 4400) SIG_NAME GND\g
J 0
(-615 4410);
DISPLAY 0.659574 (-615 4410);
PAINT MONO (-615 4410);
DISPLAY INVISIBLE (-615 4410);
FORCEPROP 2 LAST CDS_LIB pure_quanta_power
J 0
(-625 4350);
DISPLAY INVISIBLE (-625 4350);
FORCEPROP 1 LAST HDL_POWER GND
J 1
(-600 4275);
DISPLAY 0.872340 (-600 4275);
PAINT GREEN (-600 4275);
DISPLAY INVISIBLE (-600 4275);
FORCEPROP 1 LAST PATH I70
J 0
(-550 4350);
DISPLAY 0.872340 (-550 4350);
PAINT AQUA (-550 4350);
DISPLAY INVISIBLE (-550 4350);
FORCEADD Q_CAP..1
(-625 4700);
FORCEPROP 1 LAST LOCATION PC304_3
J 0
(-575 4800);
DISPLAY 0.489362 (-575 4800);
PAINT SKYBLUE (-575 4800);
FORCEPROP 0 LAST $SEC 1
J 0
(-575 4825);
DISPLAY 0.680851 (-575 4825);
PAINT MONO (-575 4825);
DISPLAY INVISIBLE (-575 4825);
FORCEPROP 0 LAST CDS_SEC 1
J 0
(-575 4825);
DISPLAY 1.021277 (-575 4825);
DISPLAY INVISIBLE (-575 4825);
FORCEPROP 1 LASTPIN (-625 4800) $PN 1
J 0
(-615 4780);
DISPLAY 0.489362 (-615 4780);
PAINT MONO (-615 4780);
FORCEPROP 1 LASTPIN (-625 4600) $PN 2
J 0
(-615 4580);
DISPLAY 0.489362 (-615 4580);
PAINT MONO (-615 4580);
FORCEPROP 1 LAST PACK_TYPE C0805
J 0
(-575 4500);
DISPLAY 0.489362 (-575 4500);
PAINT SKYBLUE (-575 4500);
FORCEPROP 1 LAST MATERIAL X6S
J 0
(-575 4600);
DISPLAY 0.489362 (-575 4600);
PAINT SKYBLUE (-575 4600);
FORCEPROP 1 LAST TOLERANCE 20%
J 0
(-575 4650);
DISPLAY 0.489362 (-575 4650);
PAINT SKYBLUE (-575 4650);
FORCEPROP 1 LAST VALUE 22UF
J 0
(-575 4750);
DISPLAY 0.489362 (-575 4750);
PAINT SKYBLUE (-575 4750);
FORCEPROP 1 LAST VOLTAGE 4V
J 0
(-575 4700);
DISPLAY 0.489362 (-575 4700);
PAINT SKYBLUE (-575 4700);
FORCEPROP 2 LAST CDS_LIB pure_quanta
J 0
(-625 4700);
DISPLAY INVISIBLE (-625 4700);
FORCEPROP 1 LAST PATH I71
J 0
(-575 4850);
DISPLAY 0.978723 (-575 4850);
PAINT WHITE (-575 4850);
DISPLAY INVISIBLE (-575 4850);
FORCEPROP 1 LAST PART_NUMBER CH622KMEA03
J 0
(-575 4550);
DISPLAY 0.489362 (-575 4550);
PAINT SKYBLUE (-575 4550);
DISPLAY INVISIBLE (-575 4550);
FORCEADD VCC_CORE..1
(-625 5025);
FORCEPROP 3 LASTPIN (-625 4975) SIG_NAME PVDDCR_CPU0_P1\g
J 0
(-615 4985);
DISPLAY 0.659574 (-615 4985);
PAINT MONO (-615 4985);
DISPLAY INVISIBLE (-615 4985);
FORCEPROP 1 LAST HDL_POWER PVDDCR_CPU0_P1
J 1
(-625 5075);
DISPLAY 0.489362 (-625 5075);
PAINT GREEN (-625 5075);
FORCEPROP 2 LAST CDS_LIB pure_quanta_power
J 0
(-625 5025);
DISPLAY INVISIBLE (-625 5025);
FORCEPROP 1 LAST PATH I72
J 0
(-575 5050);
DISPLAY 0.872340 (-575 5050);
PAINT AQUA (-575 5050);
DISPLAY INVISIBLE (-575 5050);
FORCEADD OFFPAGE..1
(-6775 975);
FORCEPROP 2 LAST $XR0 210 
J 0
(-7027 975);
DISPLAY 0.638298 (-7027 975);
PAINT MONO (-7027 975);
FORCEPROP 2 LAST CDS_LIB standard
J 2
(-6775 975);
DISPLAY INVISIBLE (-6775 975);
FORCEPROP 1 LAST OFFPAGE TRUE
J 0
(-6450 850);
DISPLAY 0.872340 (-6450 850);
PAINT GREEN (-6450 850);
DISPLAY INVISIBLE (-6450 850);
FORCEPROP 1 LAST COMMENT_BODY TRUE
J 0
(-6650 875);
DISPLAY 0.872340 (-6650 875);
PAINT GREEN (-6650 875);
DISPLAY INVISIBLE (-6650 875);
FORCEPROP 2 LAST PATH I8
J 0
(-7025 1025);
DISPLAY 0.680851 (-7025 1025);
DISPLAY INVISIBLE (-7025 1025);
FORCEADD ISL99390FRZTR5935..1
(-5675 1575);
FORCEPROP 1 LAST LOCATION PU28
J 0
(-5975 2450);
DISPLAY 0.489362 (-5975 2450);
PAINT SKYBLUE (-5975 2450);
FORCEPROP 0 LAST $SEC 1
J 0
(-5975 2600);
DISPLAY 0.680851 (-5975 2600);
PAINT MONO (-5975 2600);
DISPLAY INVISIBLE (-5975 2600);
FORCEPROP 2 LAST CDS_SEC 1
J 0
(-5975 2600);
DISPLAY 1.021277 (-5975 2600);
DISPLAY INVISIBLE (-5975 2600);
FORCEPROP 0 LASTPIN (-5275 1125) $PN 2
J 0
(-5265 1135);
DISPLAY 0.489362 (-5265 1135);
PAINT MONO (-5265 1135);
FORCEPROP 0 LASTPIN (-5275 1925) $PN 33
J 0
(-5265 1935);
DISPLAY 0.489362 (-5265 1935);
PAINT MONO (-5265 1935);
FORCEPROP 0 LASTPIN (-6125 1325) $PN 31
J 2
(-6135 1335);
DISPLAY 0.489362 (-6135 1335);
PAINT MONO (-6135 1335);
FORCEPROP 0 LASTPIN (-6125 1725) $PN 35
J 2
(-6135 1735);
DISPLAY 0.489362 (-6135 1735);
PAINT MONO (-6135 1735);
FORCEPROP 0 LASTPIN (-5275 1275) $PN 6
J 0
(-5265 1285);
DISPLAY 0.489362 (-5265 1285);
PAINT MONO (-5265 1285);
FORCEPROP 0 LASTPIN (-5275 1225) $PN 41
J 0
(-5265 1235);
DISPLAY 0.489362 (-5265 1235);
PAINT MONO (-5265 1235);
FORCEPROP 0 LASTPIN (-6125 1575) $PN 38
J 2
(-6135 1585);
DISPLAY 0.489362 (-6135 1585);
PAINT MONO (-6135 1585);
FORCEPROP 0 LASTPIN (-6125 1275) $PN 37
J 2
(-6135 1285);
DISPLAY 0.489362 (-6135 1285);
PAINT MONO (-6135 1285);
FORCEPROP 0 LASTPIN (-5275 1075) $PN 5
J 0
(-5265 1085);
DISPLAY 0.489362 (-5265 1085);
PAINT MONO (-5265 1085);
FORCEPROP 0 LASTPIN (-5275 1025) $PN 7_9-20_24
J 0
(-5265 1035);
DISPLAY 0.489362 (-5265 1035);
PAINT MONO (-5265 1035);
FORCEPROP 0 LASTPIN (-5275 975) $PN 40
J 0
(-5265 985);
DISPLAY 0.489362 (-5265 985);
PAINT MONO (-5265 985);
FORCEPROP 0 LASTPIN (-5275 1675) $PN 32
J 0
(-5265 1685);
DISPLAY 0.489362 (-5265 1685);
PAINT MONO (-5265 1685);
FORCEPROP 0 LASTPIN (-6125 2225) $PN 4
J 2
(-6135 2235);
DISPLAY 0.489362 (-6135 2235);
PAINT MONO (-6135 2235);
FORCEPROP 0 LASTPIN (-6125 975) $PN 34
J 2
(-6135 985);
DISPLAY 0.489362 (-6135 985);
PAINT MONO (-6135 985);
FORCEPROP 0 LASTPIN (-6125 1475) $PN 39
J 2
(-6135 1485);
DISPLAY 0.489362 (-6135 1485);
PAINT MONO (-6135 1485);
FORCEPROP 0 LASTPIN (-5275 1575) $PN 10_19
J 0
(-5265 1585);
DISPLAY 0.489362 (-5265 1585);
PAINT MONO (-5265 1585);
FORCEPROP 0 LASTPIN (-6125 1075) $PN 36
J 2
(-6135 1085);
DISPLAY 0.489362 (-6135 1085);
PAINT MONO (-6135 1085);
FORCEPROP 0 LASTPIN (-6125 1925) $PN 3
J 2
(-6135 1935);
DISPLAY 0.489362 (-6135 1935);
PAINT MONO (-6135 1935);
FORCEPROP 0 LASTPIN (-5275 2225) $PN 25_29
J 0
(-5265 2235);
DISPLAY 0.489362 (-5265 2235);
PAINT MONO (-5265 2235);
FORCEPROP 0 LASTPIN (-5275 2175) $PN 30
J 0
(-5265 2185);
DISPLAY 0.489362 (-5265 2185);
PAINT MONO (-5265 2185);
FORCEPROP 0 LASTPIN (-5275 1325) $PN 1
J 0
(-5265 1335);
DISPLAY 0.489362 (-5265 1335);
PAINT MONO (-5265 1335);
FORCEPROP 1 LAST MATERIAL IC
J 0
(-5975 2300);
DISPLAY 0.489362 (-5975 2300);
PAINT SKYBLUE (-5975 2300);
FORCEPROP 2 LAST VALUE ISL99390FRZ-TR5935
J 0
(-5975 2500);
DISPLAY 0.489362 (-5975 2500);
PAINT SKYBLUE (-5975 2500);
FORCEPROP 2 LAST PART_TYPE SMLF
J 0
(-5975 2550);
DISPLAY 1.021277 (-5975 2550);
FORCEPROP 1 LAST NEEDS_NO_SIZE TRUE
J 0
(-5675 1575);
DISPLAY 0.723404 (-5675 1575);
PAINT GREEN (-5675 1575);
DISPLAY INVISIBLE (-5675 1575);
FORCEPROP 1 LAST CDS_LMAN_SYM_OUTLINE -300,700,250,-650
J 0
(-5675 1575);
DISPLAY 0.468085 (-5675 1575);
PAINT GREEN (-5675 1575);
DISPLAY INVISIBLE (-5675 1575);
FORCEPROP 2 LAST CDS_LIB pure_quanta
J 0
(-5675 1575);
DISPLAY INVISIBLE (-5675 1575);
FORCEPROP 1 LAST PATH I9
J 0
(-5675 1575);
DISPLAY 0.723404 (-5675 1575);
PAINT GREEN (-5675 1575);
DISPLAY INVISIBLE (-5675 1575);
FORCEPROP 1 LAST PART_NUMBER AL099390004
J 0
(-5975 2375);
DISPLAY 0.489362 (-5975 2375);
PAINT SKYBLUE (-5975 2375);
DISPLAY INVISIBLE (-5975 2375);
FORCEADD DNS..1
(-6850 1250);
PAINT RED (-6850 1250);
FORCEPROP 2 LAST CDS_LIB mstr_misc
J 0
(-6850 1250);
DISPLAY INVISIBLE (-6850 1250);
FORCEPROP 1 LAST COMMENT_BODY TRUE
R 1
J 0
(-6775 1025);
DISPLAY 0.872340 (-6775 1025);
PAINT GREEN (-6775 1025);
DISPLAY INVISIBLE (-6775 1025);
FORCEADD DNS..1
(-4275 875);
PAINT RED (-4275 875);
FORCEPROP 2 LAST CDS_LIB mstr_misc
J 0
(-4275 875);
DISPLAY INVISIBLE (-4275 875);
FORCEPROP 1 LAST COMMENT_BODY TRUE
R 1
J 0
(-4200 650);
DISPLAY 0.872340 (-4200 650);
PAINT GREEN (-4200 650);
DISPLAY INVISIBLE (-4200 650);
FORCEADD DNS..1
(-4275 1375);
PAINT RED (-4275 1375);
FORCEPROP 2 LAST CDS_LIB mstr_misc
J 0
(-4275 1375);
DISPLAY INVISIBLE (-4275 1375);
FORCEPROP 1 LAST COMMENT_BODY TRUE
R 1
J 0
(-4200 1150);
DISPLAY 0.872340 (-4200 1150);
PAINT GREEN (-4200 1150);
DISPLAY INVISIBLE (-4200 1150);
FORCEADD DNS..1
(-4275 4175);
PAINT RED (-4275 4175);
FORCEPROP 2 LAST CDS_LIB mstr_misc
J 0
(-4275 4175);
DISPLAY INVISIBLE (-4275 4175);
FORCEPROP 1 LAST COMMENT_BODY TRUE
R 1
J 0
(-4200 3950);
DISPLAY 0.872340 (-4200 3950);
PAINT GREEN (-4200 3950);
DISPLAY INVISIBLE (-4200 3950);
FORCEADD DNS..1
(-6950 4550);
PAINT RED (-6950 4550);
FORCEPROP 2 LAST CDS_LIB mstr_misc
J 0
(-6950 4550);
DISPLAY INVISIBLE (-6950 4550);
FORCEPROP 1 LAST COMMENT_BODY TRUE
R 1
J 0
(-6875 4325);
DISPLAY 0.872340 (-6875 4325);
PAINT GREEN (-6875 4325);
DISPLAY INVISIBLE (-6875 4325);
FORCEADD DNS..1
(-4275 4675);
PAINT RED (-4275 4675);
FORCEPROP 2 LAST CDS_LIB mstr_misc
J 0
(-4275 4675);
DISPLAY INVISIBLE (-4275 4675);
FORCEPROP 1 LAST COMMENT_BODY TRUE
R 1
J 0
(-4200 4450);
DISPLAY 0.872340 (-4200 4450);
PAINT GREEN (-4200 4450);
DISPLAY INVISIBLE (-4200 4450);
FORCEADD QUANTA_TITLE_BLOCK_C..1
(0 0);
FORCEPROP 0 LAST CDS_CON_LAST_MODIFIED Thu Sep 14 16:12:41 2023
J 0
(-1885 15);
DISPLAY INVISIBLE (-1885 15);
FORCEPROP 1 LAST CUSTOM_TXT_CDS <CON_LAST_MODIFIED>
J 0
(-1885 15);
DISPLAY 0.978723 (-1885 15);
FORCEPROP 2 LAST CUSTOM_TXT_CDS <XR_PAGE_TITLE>
J 0
(-7890 5250);
DISPLAY 0.638298 (-7890 5250);
PAINT PINK (-7890 5250);
DISPLAY INVISIBLE (-7890 5250);
FORCEPROP 1 LAST CUSTOM_TXT_CDS <NAME_2>
J 0
(-3175 50);
FORCEPROP 1 LAST CUSTOM_TXT_CDS <NAME_1>
J 0
(-3175 175);
FORCEPROP 1 LAST CUSTOM_TXT_CDS <Q_NUMBER>
J 0
(-1403 103);
DISPLAY 1.212766 (-1403 103);
FORCEPROP 1 LAST CUSTOM_TXT_CDS <Q_PROJ>
J 0
(-2382 102);
DISPLAY 1.212766 (-2382 102);
FORCEPROP 1 LAST CUSTOM_TXT_CDS <Q_REV>
J 0
(-184 103);
DISPLAY 1.212766 (-184 103);
FORCEPROP 1 LAST CUSTOM_TXT_CDS <CON_PAGE_NUM> OF <CON_TOTAL_PAGES>
J 0
(-446 18);
DISPLAY 0.978723 (-446 18);
FORCEPROP 1 LAST Q_TITLE PVDDCR_CPU0_P1 VR PHASE 3&4
J 0
(-9366 26);
DISPLAY 2.446809 (-9366 26);
PAINT GREEN (-9366 26);
FORCEPROP 1 LAST CDS_LMAN_SYM_OUTLINE -9475,6775,100,-125
J 0
(0 0);
DISPLAY 0.468085 (0 0);
PAINT GREEN (0 0);
DISPLAY INVISIBLE (0 0);
FORCEPROP 2 LAST CDS_LIB pure_quanta
J 0
(0 0);
DISPLAY INVISIBLE (0 0);
FORCEPROP 2 LAST PAGE_BORDER TRUE
J 0
(-7890 5250);
DISPLAY 0.638298 (-7890 5250);
PAINT PINK (-7890 5250);
DISPLAY INVISIBLE (-7890 5250);
FORCEPROP 2 LAST CDS_XR_PAGE_TITLE CR-212 : @T6G_MB_LIB.T6G(SCH_1):PAGE212
J 0
(-7890 5250);
DISPLAY 0.638298 (-7890 5250);
PAINT PINK (-7890 5250);
DISPLAY INVISIBLE (-7890 5250);
FORCEPROP 1 LAST Q_DEPT BU9
J 1
(-3763 49);
DISPLAY 1.957447 (-3763 49);
PAINT GREEN (-3763 49);
DISPLAY INVISIBLE (-3763 49);
FORCEPROP 1 LAST COMMENT_BODY TRUE
J 0
(12 -13);
DISPLAY 0.978723 (12 -13);
PAINT GREEN (12 -13);
DISPLAY INVISIBLE (12 -13);
WIRE 16 -1 (-6800 2400)(-6800 2275);
WIRE 16 -1 (-4250 775)(-4250 700);
WIRE 16 -1 (-4250 4075)(-4250 4000);
WIRE 16 -1 (-7575 4500)(-7575 4375);
WIRE 16 -1 (-7500 1200)(-7500 1075);
WIRE 16 -1 (-7050 4575)(-7275 4575);
WIRE 16 -1 (-7275 4575)(-7275 4450);
WIRE 16 -1 (-7250 5125)(-7250 5075);
WIRE 16 -1 (-6950 1275)(-7175 1275);
WIRE 16 -1 (-7175 1275)(-7175 1150);
WIRE 16 -1 (-6900 5700)(-6900 5575);
WIRE 16 -1 (-7150 1825)(-7150 1775);
WIRE 16 -1 (-3675 2725)(-3675 2650);
WIRE 16 -1 (-3675 2650)(-3675 2575);
WIRE 16 -1 (-3975 2650)(-3675 2650);
WIRE 16 -1 (-3975 2650)(-3975 2575);
WIRE 16 -1 (-4300 2650)(-3975 2650);
WIRE 16 -1 (-4300 2575)(-4300 2650);
WIRE 16 -1 (-4625 2650)(-4300 2650);
WIRE 16 -1 (-4625 2575)(-4625 2650);
WIRE 16 -1 (-5000 2650)(-4625 2650);
WIRE 16 -1 (-5000 2575)(-5000 2650);
WIRE 16 -1 (-5175 2650)(-5000 2650);
WIRE 16 -1 (-5175 2650)(-5175 2225);
WIRE 16 -1 (-5175 2225)(-5175 2175);
WIRE 16 -1 (-5275 2225)(-5175 2225);
WIRE 16 -1 (-5175 2175)(-5275 2175);
WIRE 16 -1 (-3975 2375)(-3975 2250);
WIRE 16 -1 (-3675 2250)(-3975 2250);
WIRE 16 -1 (-4300 2250)(-3975 2250);
WIRE 16 -1 (-4300 2375)(-4300 2250);
WIRE 16 -1 (-4625 2250)(-4300 2250);
WIRE 16 -1 (-3675 2375)(-3675 2250);
WIRE 16 -1 (-3675 2250)(-3675 2175);
WIRE 16 -1 (-4625 2375)(-4625 2250);
WIRE 16 -1 (-5000 2250)(-4625 2250);
WIRE 16 -1 (-5000 2375)(-5000 2250);
WIRE 16 -1 (-5350 4625)(-4600 4625);
WIRE 16 -1 (-4600 3775)(-4600 4625);
WIRE 16 -1 (-4075 3775)(-4600 3775);
FORCEPROP 2 LAST SIG_NAME PVDDCR_CPU0_P1_VOS3
J 0
(-5235 4650);
DISPLAY 0.489362 (-5235 4650);
FORCEPROP 2 LASTPROP $XRERR UNIQUE?
J 0
(-5475 4650);
DISPLAY 0.638298 (-5475 4650);
PAINT MONO (-5475 4650);
DISPLAY INVISIBLE (-5475 4650);
WIRE 16 -1 (-5350 4875)(-4250 4875);
FORCEPROP 2 LAST SIG_NAME SW_PVDDCR_CPU0_P1_SW3
J 0
(-5235 4885);
DISPLAY 0.489362 (-5235 4885);
FORCEPROP 2 LASTPROP $XRERR UNIQUE?
J 0
(-5475 4885);
DISPLAY 0.638298 (-5475 4885);
PAINT MONO (-5475 4885);
DISPLAY INVISIBLE (-5475 4885);
WIRE 16 -1 (-4250 4875)(-2850 4875);
WIRE 16 -1 (-4250 4775)(-4250 4875);
WIRE 16 -1 (-3400 5000)(-3400 4975);
WIRE 16 -1 (-3400 4975)(-5350 4975);
FORCEPROP 2 LAST SIG_NAME SW_PVDDCR_CPU0_P1_PH3
J 0
(-5235 4985);
DISPLAY 0.489362 (-5235 4985);
FORCEPROP 2 LASTPROP $XRERR UNIQUE?
J 0
(-5475 4985);
DISPLAY 0.638298 (-5475 4985);
PAINT MONO (-5475 4985);
DISPLAY INVISIBLE (-5475 4985);
WIRE 16 -1 (-5350 5225)(-4475 5225);
FORCEPROP 2 LAST SIG_NAME SW_PVDDCR_CPU0_P1_BOOT3
J 0
(-5235 5235);
DISPLAY 0.489362 (-5235 5235);
FORCEPROP 2 LASTPROP $XRERR UNIQUE?
J 0
(-5475 5235);
DISPLAY 0.638298 (-5475 5235);
PAINT MONO (-5475 5235);
DISPLAY INVISIBLE (-5475 5235);
WIRE 16 -1 (-3400 5225)(-3400 5200);
WIRE 16 -1 (-4275 5225)(-3400 5225);
FORCEPROP 2 LAST SIG_NAME SW_PVDDCR_CPU0_P1_BOOT3_RC
J 2
(-3435 5235);
DISPLAY 0.489362 (-3435 5235);
FORCEPROP 2 LASTPROP $XRERR UNIQUE?
J 0
(-3675 5235);
DISPLAY 0.638298 (-3675 5235);
PAINT MONO (-3675 5235);
DISPLAY INVISIBLE (-3675 5235);
WIRE 16 -1 (-5275 1925)(-4400 1925);
FORCEPROP 2 LAST SIG_NAME SW_PVDDCR_CPU0_P1_BOOT4
J 0
(-5160 1935);
DISPLAY 0.489362 (-5160 1935);
FORCEPROP 2 LASTPROP $XRERR UNIQUE?
J 0
(-5400 1935);
DISPLAY 0.638298 (-5400 1935);
PAINT MONO (-5400 1935);
DISPLAY INVISIBLE (-5400 1935);
WIRE 16 -1 (-3325 1925)(-3325 1900);
WIRE 16 -1 (-4200 1925)(-3325 1925);
FORCEPROP 2 LAST SIG_NAME SW_PVDDCR_CPU0_P1_BOOT4_RC
J 2
(-3360 1935);
DISPLAY 0.489362 (-3360 1935);
FORCEPROP 2 LASTPROP $XRERR UNIQUE?
J 0
(-3600 1935);
DISPLAY 0.638298 (-3600 1935);
PAINT MONO (-3600 1935);
DISPLAY INVISIBLE (-3600 1935);
WIRE 16 -1 (-7150 2575)(-7150 2700);
WIRE 16 -1 (-6800 2700)(-7150 2700);
WIRE 16 -1 (-7150 2825)(-7150 2700);
WIRE 16 -1 (-6475 2700)(-6800 2700);
WIRE 16 -1 (-6800 2600)(-6800 2700);
WIRE 16 -1 (-6475 2225)(-6475 2700);
WIRE 16 -1 (-6475 2225)(-6125 2225);
WIRE 16 -1 (-5275 975)(-5125 975);
WIRE 16 -1 (-5125 975)(-5125 1025);
WIRE 16 -1 (-5125 875)(-5125 975);
WIRE 16 -1 (-5125 1025)(-5125 1075);
WIRE 16 -1 (-5275 1025)(-5125 1025);
WIRE 16 -1 (-5125 1125)(-5125 1075);
WIRE 16 -1 (-5275 1075)(-5125 1075);
WIRE 16 -1 (-5125 1125)(-5275 1125);
WIRE 16 -1 (-7250 5875)(-7250 6000);
WIRE 16 -1 (-6900 6000)(-7250 6000);
WIRE 16 -1 (-7250 6125)(-7250 6000);
WIRE 16 -1 (-6550 6000)(-6900 6000);
WIRE 16 -1 (-6900 5900)(-6900 6000);
WIRE 16 -1 (-6550 5525)(-6550 6000);
WIRE 16 -1 (-6550 5525)(-6200 5525);
WIRE 16 -1 (-5350 4275)(-5200 4275);
WIRE 16 -1 (-5200 4275)(-5200 4325);
WIRE 16 -1 (-5200 4150)(-5200 4275);
WIRE 16 -1 (-5200 4325)(-5200 4375);
WIRE 16 -1 (-5350 4325)(-5200 4325);
WIRE 16 -1 (-5200 4425)(-5200 4375);
WIRE 16 -1 (-5350 4375)(-5200 4375);
WIRE 16 -1 (-5200 4425)(-5350 4425);
WIRE 16 -1 (-1950 1325)(-1525 1325);
WIRE 16 -1 (-1525 1250)(-1525 1325);
WIRE 16 -1 (-575 1300)(-575 1175);
WIRE 16 -1 (-575 1100)(-575 1175);
WIRE 16 -1 (-575 1175)(-1000 1175);
WIRE 16 -1 (-1000 1300)(-1000 1175);
WIRE 16 -1 (-1250 1575)(-1000 1575);
WIRE 16 -1 (-1950 1575)(-1250 1575);
WIRE 16 -1 (-1250 1575)(-1250 475);
WIRE 16 -1 (-1000 1575)(-575 1575);
WIRE 16 -1 (-1000 1575)(-1000 1500);
WIRE 16 -1 (-575 1675)(-575 1575);
WIRE 16 -1 (-575 1575)(-575 1500);
WIRE 16 -1 (-1250 475)(-3825 475);
WIRE 16 -1 (-4125 5675)(-4125 5550);
WIRE 16 -1 (-3825 5550)(-4125 5550);
WIRE 16 -1 (-4450 5550)(-4125 5550);
WIRE 16 -1 (-4450 5675)(-4450 5550);
WIRE 16 -1 (-4775 5550)(-4450 5550);
WIRE 16 -1 (-3825 5675)(-3825 5550);
WIRE 16 -1 (-3825 5550)(-3825 5500);
WIRE 16 -1 (-4775 5675)(-4775 5550);
WIRE 16 -1 (-5125 5550)(-4775 5550);
WIRE 16 -1 (-5125 5675)(-5125 5550);
WIRE 16 -1 (-3825 6025)(-3825 5950);
WIRE 16 -1 (-3825 5950)(-3825 5875);
WIRE 16 -1 (-4125 5950)(-3825 5950);
WIRE 16 -1 (-4125 5950)(-4125 5875);
WIRE 16 -1 (-4450 5950)(-4125 5950);
WIRE 16 -1 (-4450 5875)(-4450 5950);
WIRE 16 -1 (-4775 5950)(-4450 5950);
WIRE 16 -1 (-4775 5875)(-4775 5950);
WIRE 16 -1 (-5125 5950)(-4775 5950);
WIRE 16 -1 (-5125 5875)(-5125 5950);
WIRE 16 -1 (-5250 5950)(-5125 5950);
WIRE 16 -1 (-5250 5950)(-5250 5525);
WIRE 16 -1 (-5350 5525)(-5250 5525);
WIRE 16 -1 (-5250 5525)(-5250 5475);
WIRE 16 -1 (-5350 5475)(-5250 5475);
WIRE 16 -1 (-625 4600)(-625 4475);
WIRE 16 -1 (-625 4400)(-625 4475);
WIRE 16 -1 (-625 4475)(-1050 4475);
WIRE 16 -1 (-1050 4600)(-1050 4475);
WIRE 16 -1 (-1175 4875)(-1050 4875);
WIRE 16 -1 (-2050 4875)(-1175 4875);
WIRE 16 -1 (-1175 4875)(-1175 3775);
WIRE 16 -1 (-1050 4875)(-625 4875);
WIRE 16 -1 (-1050 4875)(-1050 4800);
WIRE 16 -1 (-625 4975)(-625 4875);
WIRE 16 -1 (-625 4875)(-625 4800);
WIRE 16 -1 (-1175 3775)(-3875 3775);
WIRE 16 -1 (-3325 1700)(-3325 1675);
WIRE 16 -1 (-3325 1675)(-5275 1675);
FORCEPROP 2 LAST SIG_NAME SW_PVDDCR_CPU0_P1_PH4
J 0
(-5160 1685);
DISPLAY 0.489362 (-5160 1685);
FORCEPROP 2 LASTPROP $XRERR UNIQUE?
J 0
(-5400 1685);
DISPLAY 0.638298 (-5400 1685);
PAINT MONO (-5400 1685);
DISPLAY INVISIBLE (-5400 1685);
WIRE 16 -1 (-5275 1575)(-4250 1575);
FORCEPROP 2 LAST SIG_NAME SW_PVDDCR_CPU0_P1_SW4
J 0
(-5160 1585);
DISPLAY 0.489362 (-5160 1585);
FORCEPROP 2 LASTPROP $XRERR UNIQUE?
J 0
(-5400 1585);
DISPLAY 0.638298 (-5400 1585);
PAINT MONO (-5400 1585);
DISPLAY INVISIBLE (-5400 1585);
WIRE 16 -1 (-4250 1575)(-2750 1575);
WIRE 16 -1 (-4250 1475)(-4250 1575);
WIRE 16 -1 (-2050 4625)(-1525 4625);
FORCEPROP 2 LAST SIG_NAME IND_CPU0_P1_CPL3
J 0
(-1960 4635);
DISPLAY 0.489362 (-1960 4635);
WIRE 16 -1 (-3350 4625)(-2850 4625);
FORCEPROP 2 LAST SIG_NAME IND_CPU0_P1_CPL2
J 0
(-3335 4635);
DISPLAY 0.489362 (-3335 4635);
WIRE 16 -1 (-3200 1325)(-2750 1325);
FORCEPROP 2 LAST SIG_NAME IND_CPU0_P1_CPL3
J 0
(-3185 1335);
DISPLAY 0.489362 (-3185 1335);
WIRE 16 -1 (-4250 4575)(-4250 4275);
FORCEPROP 2 LAST SIG_NAME SW_PVDDCR_CPU0_P1_SW3_RC
J 0
(-4210 4385);
DISPLAY 0.489362 (-4210 4385);
FORCEPROP 2 LASTPROP $XRERR UNIQUE?
J 0
(-4450 4385);
DISPLAY 0.638298 (-4450 4385);
PAINT MONO (-4450 4385);
DISPLAY INVISIBLE (-4450 4385);
WIRE 16 -1 (-5350 4575)(-4825 4575);
FORCEPROP 2 LAST SIG_NAME NC_PVDDCR_CPU0_P1_GL1_3
J 0
(-5235 4585);
DISPLAY 0.489362 (-5235 4585);
FORCEPROP 2 LASTPROP $XRERR UNIQUE?
J 0
(-4795 4575);
DISPLAY 0.638298 (-4795 4575);
PAINT MONO (-4795 4575);
DISPLAY INVISIBLE (-4795 4575);
WIRE 16 -1 (-5350 4525)(-4825 4525);
FORCEPROP 2 LAST SIG_NAME NC_PVDDCR_CPU0_P1_GL2_3
J 0
(-5235 4535);
DISPLAY 0.489362 (-5235 4535);
FORCEPROP 2 LASTPROP $XRERR UNIQUE?
J 0
(-4795 4525);
DISPLAY 0.638298 (-4795 4525);
PAINT MONO (-4795 4525);
DISPLAY INVISIBLE (-4795 4525);
WIRE 16 -1 (-7250 5400)(-6750 5400);
WIRE 16 -1 (-7250 5675)(-7250 5400);
WIRE 16 -1 (-7250 5400)(-7250 5325);
WIRE 16 -1 (-6750 5400)(-6750 5225);
FORCEPROP 2 LAST SIG_NAME PVDDCR_CPU0_P1_VCC3
J 2
(-6285 5235);
DISPLAY 0.489362 (-6285 5235);
FORCEPROP 2 LASTPROP $XRERR UNIQUE?
J 0
(-6525 5235);
DISPLAY 0.638298 (-6525 5235);
PAINT MONO (-6525 5235);
DISPLAY INVISIBLE (-6525 5235);
WIRE 16 -1 (-6750 5225)(-6200 5225);
WIRE 16 -1 (-6750 5225)(-6750 5025);
WIRE 16 -1 (-6750 5025)(-6200 5025);
WIRE 16 -1 (-6200 4875)(-6850 4875);
FORCEPROP 2 LAST SIG_NAME PVDDCR_CPU0_P1_IMON3
J 2
(-6285 4885);
DISPLAY 0.489362 (-6285 4885);
WIRE 16 -1 (-6200 4375)(-6825 4375);
FORCEPROP 2 LAST SIG_NAME PVDDCR_CPU0_P1_TEMP0
J 2
(-6285 4385);
DISPLAY 0.489362 (-6285 4385);
WIRE 16 -1 (-6200 4275)(-6800 4275);
FORCEPROP 2 LAST SIG_NAME PVDDCR_CPU0_P1_PWM3
J 2
(-6285 4285);
DISPLAY 0.489362 (-6285 4285);
WIRE 16 -1 (-6200 4625)(-6650 4625);
FORCEPROP 2 LAST SIG_NAME NC_PVDDCR_CPU0_P1_DNC3
J 2
(-6285 4635);
DISPLAY 0.489362 (-6285 4635);
FORCEPROP 2 LASTPROP $XRERR UNIQUE?
J 0
(-6890 4625);
DISPLAY 0.638298 (-6890 4625);
PAINT MONO (-6890 4625);
DISPLAY INVISIBLE (-6890 4625);
WIRE 16 -1 (-6850 4575)(-6200 4575);
FORCEPROP 2 LAST SIG_NAME PVDDCR_CPU0_P1_LSET3
J 2
(-6285 4585);
DISPLAY 0.489362 (-6285 4585);
FORCEPROP 2 LASTPROP $XRERR UNIQUE?
J 0
(-6525 4585);
DISPLAY 0.638298 (-6525 4585);
PAINT MONO (-6525 4585);
DISPLAY INVISIBLE (-6525 4585);
WIRE 16 -1 (-7575 4700)(-7575 4775);
WIRE 16 -1 (-6200 4775)(-7575 4775);
FORCEPROP 2 LAST SIG_NAME PVDDCR_CPU0_P1_VCCS
J 2
(-6285 4785);
DISPLAY 0.489362 (-6285 4785);
WIRE 16 -1 (-7750 4775)(-7575 4775);
WIRE 16 -1 (-4250 1275)(-4250 975);
FORCEPROP 2 LAST SIG_NAME SW_PVDDCR_CPU0_P1_SW4_RC
J 0
(-4210 1085);
DISPLAY 0.489362 (-4210 1085);
FORCEPROP 2 LASTPROP $XRERR UNIQUE?
J 0
(-4450 1085);
DISPLAY 0.638298 (-4450 1085);
PAINT MONO (-4450 1085);
DISPLAY INVISIBLE (-4450 1085);
WIRE 16 -1 (-4025 475)(-4525 475);
FORCEPROP 2 LAST SIG_NAME PVDDCR_CPU0_P1_VOS4
J 0
(-5160 1350);
DISPLAY 0.489362 (-5160 1350);
FORCEPROP 2 LASTPROP $XRERR UNIQUE?
J 0
(-5400 1350);
DISPLAY 0.638298 (-5400 1350);
PAINT MONO (-5400 1350);
DISPLAY INVISIBLE (-5400 1350);
WIRE 16 -1 (-4525 475)(-4525 1325);
WIRE 16 -1 (-5275 1325)(-4525 1325);
WIRE 16 -1 (-5275 1225)(-4750 1225);
FORCEPROP 2 LAST SIG_NAME NC_PVDDCR_CPU0_P1_GL2_4
J 0
(-5160 1235);
DISPLAY 0.489362 (-5160 1235);
FORCEPROP 2 LASTPROP $XRERR UNIQUE?
J 0
(-4720 1225);
DISPLAY 0.638298 (-4720 1225);
PAINT MONO (-4720 1225);
DISPLAY INVISIBLE (-4720 1225);
WIRE 16 -1 (-5275 1275)(-4750 1275);
FORCEPROP 2 LAST SIG_NAME NC_PVDDCR_CPU0_P1_GL1_4
J 0
(-5160 1285);
DISPLAY 0.489362 (-5160 1285);
FORCEPROP 2 LASTPROP $XRERR UNIQUE?
J 0
(-4720 1275);
DISPLAY 0.638298 (-4720 1275);
PAINT MONO (-4720 1275);
DISPLAY INVISIBLE (-4720 1275);
WIRE 16 -1 (-7150 2100)(-6725 2100);
WIRE 16 -1 (-7150 2375)(-7150 2100);
WIRE 16 -1 (-7150 2100)(-7150 2025);
WIRE 16 -1 (-6725 2100)(-6725 1925);
FORCEPROP 2 LAST SIG_NAME PVDDCR_CPU0_P1_VCC4
J 2
(-6210 1935);
DISPLAY 0.489362 (-6210 1935);
FORCEPROP 2 LASTPROP $XRERR UNIQUE?
J 0
(-6450 1935);
DISPLAY 0.638298 (-6450 1935);
PAINT MONO (-6450 1935);
DISPLAY INVISIBLE (-6450 1935);
WIRE 16 -1 (-6725 1925)(-6125 1925);
WIRE 16 -1 (-6725 1925)(-6725 1725);
WIRE 16 -1 (-6725 1725)(-6125 1725);
WIRE 16 -1 (-6125 1075)(-6750 1075);
FORCEPROP 2 LAST SIG_NAME PVDDCR_CPU0_P1_TEMP0
J 2
(-6185 1085);
DISPLAY 0.489362 (-6185 1085);
WIRE 16 -1 (-6750 1275)(-6125 1275);
FORCEPROP 2 LAST SIG_NAME PVDDCR_CPU0_P1_LSET4
J 2
(-6185 1285);
DISPLAY 0.489362 (-6185 1285);
FORCEPROP 2 LASTPROP $XRERR UNIQUE?
J 0
(-6425 1285);
DISPLAY 0.638298 (-6425 1285);
PAINT MONO (-6425 1285);
DISPLAY INVISIBLE (-6425 1285);
WIRE 16 -1 (-6125 1325)(-6575 1325);
FORCEPROP 2 LAST SIG_NAME NC_PVDDCR_CPU0_P1_DNC4
J 2
(-6185 1335);
DISPLAY 0.489362 (-6185 1335);
FORCEPROP 2 LASTPROP $XRERR UNIQUE?
J 0
(-6815 1325);
DISPLAY 0.638298 (-6815 1325);
PAINT MONO (-6815 1325);
DISPLAY INVISIBLE (-6815 1325);
WIRE 16 -1 (-6125 1575)(-6775 1575);
FORCEPROP 2 LAST SIG_NAME PVDDCR_CPU0_P1_IMON4
J 2
(-6185 1585);
DISPLAY 0.489362 (-6185 1585);
WIRE 16 -1 (-6125 975)(-6725 975);
FORCEPROP 2 LAST SIG_NAME PVDDCR_CPU0_P1_PWM4
J 2
(-6185 985);
DISPLAY 0.489362 (-6185 985);
WIRE 16 -1 (-7500 1400)(-7500 1475);
WIRE 16 -1 (-6125 1475)(-7500 1475);
FORCEPROP 2 LAST SIG_NAME PVDDCR_CPU0_P1_VCCS
J 2
(-6185 1485);
DISPLAY 0.489362 (-6185 1485);
WIRE 16 -1 (-7675 1475)(-7500 1475);
DOT 1 (-575 1175);
DOT 1 (-625 4875);
DOT 1 (-625 4475);
DOT 1 (-1050 4875);
DOT 1 (-1175 4875);
DOT 1 (-3825 5550);
DOT 1 (-575 1575);
DOT 1 (-1000 1575);
DOT 1 (-1250 1575);
DOT 1 (-3675 2650);
DOT 1 (-3675 2250);
DOT 1 (-4125 5950);
DOT 1 (-4125 5550);
DOT 1 (-4450 5950);
DOT 1 (-4775 5950);
DOT 1 (-4775 5550);
DOT 1 (-5125 5950);
DOT 1 (-5250 5525);
DOT 1 (-5200 4375);
DOT 1 (-5200 4325);
DOT 1 (-5200 4275);
DOT 1 (-6900 6000);
DOT 1 (-6750 5225);
DOT 1 (-7250 6000);
DOT 1 (-7250 5400);
DOT 1 (-7575 4775);
DOT 1 (-3975 2650);
DOT 1 (-4300 2650);
DOT 1 (-4625 2650);
DOT 1 (-4625 2250);
DOT 1 (-5000 2650);
DOT 1 (-5175 2225);
DOT 1 (-4250 1575);
DOT 1 (-5125 1025);
DOT 1 (-5125 1075);
DOT 1 (-5125 975);
DOT 1 (-6800 2700);
DOT 1 (-7150 2700);
DOT 1 (-7150 2100);
DOT 1 (-6725 1925);
DOT 1 (-7500 1475);
DOT 1 (-3825 5950);
DOT 1 (-4450 5550);
DOT 1 (-3975 2250);
DOT 1 (-4300 2250);
DOT 1 (-4250 4875);
FORCENOTE
PVDDCR_CPU0_P1_PHASE4
(-6375 2900) 0;
DISPLAY LEFT (-6375 2900);
DISPLAY 1.595745 (-6375 2900);
PAINT WHITE (-6375 2900);
FORCENOTE
2ND=CV+15^0TZ01
(-2025 4950) 0;
DISPLAY LEFT (-2025 4950);
DISPLAY 0.638298 (-2025 4950);
PAINT WHITE (-2025 4950);
FORCENOTE
ISAT:70A@100C
(-2025 5150) 0;
DISPLAY LEFT (-2025 5150);
DISPLAY 0.638298 (-2025 5150);
PAINT WHITE (-2025 5150);
FORCENOTE
DCR=1-4,0.105M OHM
(-2025 5050) 0;
DISPLAY LEFT (-2025 5050);
DISPLAY 0.638298 (-2025 5050);
PAINT WHITE (-2025 5050);
FORCENOTE
DCR=2-3,0.27M OHM
(-2025 5000) 0;
DISPLAY LEFT (-2025 5000);
DISPLAY 0.638298 (-2025 5000);
PAINT WHITE (-2025 5000);
FORCENOTE
11.0*7.5*12.5
(-2025 5100) 0;
DISPLAY LEFT (-2025 5100);
DISPLAY 0.638298 (-2025 5100);
PAINT WHITE (-2025 5100);
FORCENOTE
PGL6303.151HLT
(-2025 5200) 0;
DISPLAY LEFT (-2025 5200);
DISPLAY 0.638298 (-2025 5200);
PAINT WHITE (-2025 5200);
FORCENOTE
PGL6303.151HLT
(-1950 1900) 0;
DISPLAY LEFT (-1950 1900);
DISPLAY 0.638298 (-1950 1900);
PAINT WHITE (-1950 1900);
FORCENOTE
ISAT:70A@100C
(-1950 1850) 0;
DISPLAY LEFT (-1950 1850);
DISPLAY 0.638298 (-1950 1850);
PAINT WHITE (-1950 1850);
FORCENOTE
DCR=1-4,0.105M OHM
(-1950 1750) 0;
DISPLAY LEFT (-1950 1750);
DISPLAY 0.638298 (-1950 1750);
PAINT WHITE (-1950 1750);
FORCENOTE
DCR=2-3,0.27M OHM
(-1950 1700) 0;
DISPLAY LEFT (-1950 1700);
DISPLAY 0.638298 (-1950 1700);
PAINT WHITE (-1950 1700);
FORCENOTE
2ND=CV+15^0TZ01
(-1950 1650) 0;
DISPLAY LEFT (-1950 1650);
DISPLAY 0.638298 (-1950 1650);
PAINT WHITE (-1950 1650);
FORCENOTE
11.0*7.5*12.5
(-1950 1800) 0;
DISPLAY LEFT (-1950 1800);
DISPLAY 0.638298 (-1950 1800);
PAINT WHITE (-1950 1800);
FORCENOTE
PVDDCR_CPU0_P1_PHASE3
(-6350 6275) 0;
DISPLAY LEFT (-6350 6275);
DISPLAY 1.595745 (-6350 6275);
PAINT WHITE (-6350 6275);
QUIT
